FILE_TYPE = MACRO_DRAWING;
SET COLOR_WIRE YELLOW;
SET COLOR_PROP MONO;
SET COLOR_DOT WHITE;
SET COLOR_ARC YELLOW;
SET COLOR_BODY GREEN;
SET COLOR_NOTE MONO;
SET PROP_DISPLAY VALUE;
SET PAGE_NUMBER P212;
FORCEADD IR354XX..1
(825 3775);
FORCEPROP 2 LASTPIN (1325 4325) $PN 38
J 0
(1335 4335);
DISPLAY 0.617021 (1335 4335);
PAINT MONO (1335 4335);
FORCEPROP 2 LASTPIN (1325 3275) $PN 7
J 0
(1335 3285);
DISPLAY 0.617021 (1335 3285);
PAINT MONO (1335 3285);
FORCEPROP 2 LASTPIN (1325 4075) $PN 31
J 0
(1335 4085);
DISPLAY 0.617021 (1335 4085);
PAINT MONO (1335 4085);
FORCEPROP 2 LASTPIN (325 3425) $PN 32
J 2
(315 3435);
DISPLAY 0.617021 (315 3435);
PAINT MONO (315 3435);
FORCEPROP 2 LASTPIN (325 3475) $PN 33
J 2
(315 3485);
DISPLAY 0.617021 (315 3485);
PAINT MONO (315 3485);
FORCEPROP 2 LASTPIN (325 3575) $PN 39
J 2
(315 3585);
DISPLAY 0.617021 (315 3585);
PAINT MONO (315 3585);
FORCEPROP 2 LASTPIN (325 3775) $PN 6
J 2
(315 3785);
DISPLAY 0.617021 (315 3785);
PAINT MONO (315 3785);
FORCEPROP 2 LASTPIN (325 3825) $PN 41
J 2
(315 3835);
DISPLAY 0.617021 (315 3835);
PAINT MONO (315 3835);
FORCEPROP 2 LASTPIN (325 4025) $PN 35
J 2
(315 4035);
DISPLAY 0.617021 (315 4035);
PAINT MONO (315 4035);
FORCEPROP 2 LASTPIN (325 3925) $PN 1
J 2
(315 3935);
DISPLAY 0.617021 (315 3935);
PAINT MONO (315 3935);
FORCEPROP 1 LAST PART_NUMBER H73684-001
J 0
(375 3075);
DISPLAY 0.617021 (375 3075);
PAINT BLUE (375 3075);
FORCEPROP 2 LASTPIN (1325 3225) $PN 5
J 0
(1335 3235);
DISPLAY 0.617021 (1335 3235);
PAINT MONO (1335 3235);
FORCEPROP 2 LASTPIN (1325 3475) $PN 10
J 0
(1335 3485);
DISPLAY 0.617021 (1335 3485);
PAINT MONO (1335 3485);
FORCEPROP 2 LASTPIN (1325 3325) $PN 40
J 0
(1335 3335);
DISPLAY 0.617021 (1335 3335);
PAINT MONO (1335 3335);
FORCEPROP 2 LASTPIN (1325 3375) $PN 2
J 0
(1335 3385);
DISPLAY 0.617021 (1335 3385);
PAINT MONO (1335 3385);
FORCEPROP 2 LASTPIN (1325 3825) $PN 36
J 0
(1335 3835);
DISPLAY 0.617021 (1335 3835);
PAINT MONO (1335 3835);
FORCEPROP 2 LASTPIN (325 4125) $PN 4
J 2
(315 4135);
DISPLAY 0.617021 (315 4135);
PAINT MONO (315 4135);
FORCEPROP 2 LASTPIN (325 4225) $PN 25
J 2
(315 4235);
DISPLAY 0.617021 (315 4235);
PAINT MONO (315 4235);
FORCEPROP 2 LASTPIN (325 4275) $PN 30
J 2
(315 4285);
DISPLAY 0.617021 (315 4285);
PAINT MONO (315 4285);
FORCEPROP 2 LASTPIN (325 4325) $PN 3
J 2
(315 4335);
DISPLAY 0.617021 (315 4335);
PAINT MONO (315 4335);
FORCEPROP 1 LAST MATERIAL IC
J 0
(375 4525);
DISPLAY 0.617021 (375 4525);
PAINT SKYBLUE (375 4525);
FORCEPROP 2 LAST NO_XNET_CONNECTION 1
J 0
(375 4625);
PAINT MONO (375 4625);
FORCEPROP 1 LAST LOCATION EU7C1
J 0
(375 4575);
DISPLAY 0.617021 (375 4575);
PAINT AQUA (375 4575);
FORCEPROP 1 LAST VALUE IR35412
J 1
(825 4400);
DISPLAY 0.617021 (825 4400);
PAINT SKYBLUE (825 4400);
FORCEPROP 2 LASTPIN (1325 4125) $PN 37
J 0
(1335 4135);
DISPLAY 0.617021 (1335 4135);
PAINT MONO (1335 4135);
FORCEPROP 2 LASTPIN (325 3675) $PN 34
J 2
(315 3685);
DISPLAY 0.617021 (315 3685);
PAINT MONO (315 3685);
FORCEPROP 2 LAST CDS_LIB mstr_discrete
J 0
(825 3775);
PAINT ORANGE (825 3775);
DISPLAY INVISIBLE (825 3775);
FORCEPROP 2 LAST CDS_LOCATION EU7C1
J 0
(375 4575);
PAINT GREEN (375 4575);
DISPLAY INVISIBLE (375 4575);
FORCEPROP 2 LAST CDS_SEC 1
J 0
(375 4625);
PAINT MONO (375 4625);
DISPLAY INVISIBLE (375 4625);
FORCEPROP 2 LAST $SEC 1
J 0
(375 4625);
PAINT MONO (375 4625);
DISPLAY INVISIBLE (375 4625);
FORCEPROP 1 LAST PACK_TYPE SM
J 0
(375 4625);
PAINT SKYBLUE (375 4625);
DISPLAY INVISIBLE (375 4625);
FORCEPROP 1 LAST PATH I101
J 0
(825 4525);
PAINT GREEN (825 4525);
DISPLAY INVISIBLE (825 4525);
FORCEADD GND..1
(3100 3700);
FORCEPROP 3 LASTPIN (3100 3750) SIG_NAME GND\g
J 0
(3110 3760);
DISPLAY 0.659574 (3110 3760);
PAINT MONO (3110 3760);
DISPLAY INVISIBLE (3110 3760);
FORCEPROP 2 LAST ROOM PVSA_CPU1_PWR_VR
J 0
(2550 3775);
DISPLAY 1.936170 (2550 3775);
PAINT ORANGE (2550 3775);
DISPLAY INVISIBLE (2550 3775);
FORCEPROP 2 LAST BOM_COST PROC_VRD_VCCIN_CPU0
J 0
(2725 3775);
DISPLAY 1.446809 (2725 3775);
PAINT MONO (2725 3775);
DISPLAY INVISIBLE (2725 3775);
FORCEPROP 1 LAST SIZE 1B
J 0
(3175 3650);
DISPLAY 1.723404 (3175 3650);
PAINT GREEN (3175 3650);
DISPLAY INVISIBLE (3175 3650);
FORCEPROP 2 LAST CDS_LIB mstr_symbols
J 0
(3100 3700);
PAINT ORANGE (3100 3700);
DISPLAY INVISIBLE (3100 3700);
FORCEPROP 1 LAST PATH I102
J 0
(3175 3700);
DISPLAY 0.872340 (3175 3700);
PAINT AQUA (3175 3700);
DISPLAY INVISIBLE (3175 3700);
FORCEPROP 1 LAST VOLTAGE 0
J 0
(3100 3700);
PAINT SKYBLUE (3100 3700);
DISPLAY INVISIBLE (3100 3700);
FORCEPROP 1 LAST BODY_TYPE PLUMBING
J 0
(3055 3657);
DISPLAY 0.340426 (3055 3657);
PAINT GREEN (3055 3657);
DISPLAY INVISIBLE (3055 3657);
FORCEPROP 1 LAST HDL_POWER GND
J 0
(3100 3850);
DISPLAY 1.723404 (3100 3850);
PAINT GREEN (3100 3850);
DISPLAY INVISIBLE (3100 3850);
FORCEADD RES..2
(3100 3950);
FORCEPROP 1 LAST PART_NUMBER G21796-187
J 0
(3140 3825);
DISPLAY 0.617021 (3140 3825);
PAINT BLUE (3140 3825);
FORCEPROP 1 LAST WATTAGE 1/16W
J 0
(3140 3925);
DISPLAY 0.617021 (3140 3925);
PAINT SKYBLUE (3140 3925);
FORCEPROP 1 LAST TOLERANCE 1%
J 0
(3145 3975);
DISPLAY 0.617021 (3145 3975);
PAINT SKYBLUE (3145 3975);
FORCEPROP 1 LAST VALUE 68.1K
J 0
(3145 4025);
DISPLAY 0.617021 (3145 4025);
PAINT SKYBLUE (3145 4025);
FORCEPROP 1 LAST MATERIAL EMPTY
J 0
(3140 3875);
DISPLAY 0.617021 (3140 3875);
PAINT RED (3140 3875);
FORCEPROP 1 LAST LOCATION R7C25
J 0
(3145 4075);
DISPLAY 0.617021 (3145 4075);
PAINT AQUA (3145 4075);
FORCEPROP 1 LAST PACK_TYPE 0402
J 0
(3140 3775);
DISPLAY 0.617021 (3140 3775);
PAINT SKYBLUE (3140 3775);
FORCEPROP 1 LASTPIN (3100 3850) $PN 2
J 0
(3105 3860);
DISPLAY 0.787234 (3105 3860);
PAINT ORANGE (3105 3860);
DISPLAY INVISIBLE (3105 3860);
FORCEPROP 2 LAST CDS_LIB mstr_discrete
J 0
(3100 3950);
PAINT ORANGE (3100 3950);
DISPLAY INVISIBLE (3100 3950);
FORCEPROP 1 LASTPIN (3100 4050) $PN 1
J 0
(3105 4012);
DISPLAY 0.787234 (3105 4012);
PAINT ORANGE (3105 4012);
DISPLAY INVISIBLE (3105 4012);
FORCEPROP 2 LAST CDS_SEC 1
J 0
(3150 4175);
PAINT MONO (3150 4175);
DISPLAY INVISIBLE (3150 4175);
FORCEPROP 2 LAST $SEC 1
J 0
(3150 4175);
PAINT MONO (3150 4175);
DISPLAY INVISIBLE (3150 4175);
FORCEPROP 1 LAST PATH I103
J 0
(3150 4125);
DISPLAY 0.978723 (3150 4125);
PAINT WHITE (3150 4125);
DISPLAY INVISIBLE (3150 4125);
FORCEADD SHUNT..1
(-1300 1850);
FORCEPROP 1 LAST PART_NUMBER N_A
J 0
(-1375 1760);
DISPLAY 0.617021 (-1375 1760);
PAINT BLUE (-1375 1760);
FORCEPROP 1 LASTPIN (-1450 1850) $PN 1
J 2
(-1400 1860);
DISPLAY 0.617021 (-1400 1860);
PAINT ORANGE (-1400 1860);
FORCEPROP 1 LAST LOCATION SH3P1
J 0
(-1375 1900);
DISPLAY 0.617021 (-1375 1900);
PAINT AQUA (-1375 1900);
FORCEPROP 1 LASTPIN (-1150 1850) $PN 2
J 0
(-1190 1860);
DISPLAY 0.617021 (-1190 1860);
PAINT ORANGE (-1190 1860);
FORCEPROP 1 LAST MATERIAL EMPTY
J 0
(-1375 1715);
DISPLAY 0.978723 (-1375 1715);
PAINT RED (-1375 1715);
DISPLAY INVISIBLE (-1375 1715);
FORCEPROP 1 LAST PACK_TYPE SH0201
J 0
(-1360 1665);
DISPLAY 0.978723 (-1360 1665);
PAINT SKYBLUE (-1360 1665);
DISPLAY INVISIBLE (-1360 1665);
FORCEPROP 1 LAST PIN_SHORT A:B
J 0
(-1375 1600);
DISPLAY 1.021277 (-1375 1600);
PAINT ORANGE (-1375 1600);
DISPLAY INVISIBLE (-1375 1600);
FORCEPROP 2 LAST CDS_LIB mstr_misc
J 0
(-1300 1850);
PAINT ORANGE (-1300 1850);
DISPLAY INVISIBLE (-1300 1850);
FORCEPROP 1 LAST PATH I104
J 0
(-1350 1950);
DISPLAY 0.978723 (-1350 1950);
PAINT ORANGE (-1350 1950);
DISPLAY INVISIBLE (-1350 1950);
FORCEPROP 0 LAST SEC 1
J 0
(-1375 1950);
DISPLAY 0.680851 (-1375 1950);
PAINT MONO (-1375 1950);
DISPLAY INVISIBLE (-1375 1950);
FORCEPROP 2 LAST SEC_TYPE SH0201
J 0
(-1350 2000);
DISPLAY 1.021277 (-1350 2000);
PAINT ORANGE (-1350 2000);
DISPLAY INVISIBLE (-1350 2000);
FORCEADD SHUNT..1
(-1300 1400);
FORCEPROP 1 LAST LOCATION SH3P2
J 0
(-1375 1450);
DISPLAY 0.617021 (-1375 1450);
PAINT AQUA (-1375 1450);
FORCEPROP 1 LAST PART_NUMBER N_A
J 0
(-1375 1310);
DISPLAY 0.617021 (-1375 1310);
PAINT BLUE (-1375 1310);
FORCEPROP 1 LASTPIN (-1150 1400) $PN 2
J 0
(-1190 1410);
DISPLAY 0.617021 (-1190 1410);
PAINT ORANGE (-1190 1410);
FORCEPROP 1 LASTPIN (-1450 1400) $PN 1
J 2
(-1400 1410);
DISPLAY 0.617021 (-1400 1410);
PAINT ORANGE (-1400 1410);
FORCEPROP 1 LAST PIN_SHORT A:B
J 0
(-1375 1150);
DISPLAY 1.021277 (-1375 1150);
PAINT ORANGE (-1375 1150);
DISPLAY INVISIBLE (-1375 1150);
FORCEPROP 1 LAST PACK_TYPE SH0201
J 0
(-1360 1215);
DISPLAY 0.978723 (-1360 1215);
PAINT SKYBLUE (-1360 1215);
DISPLAY INVISIBLE (-1360 1215);
FORCEPROP 1 LAST MATERIAL EMPTY
J 0
(-1375 1265);
DISPLAY 0.978723 (-1375 1265);
PAINT RED (-1375 1265);
DISPLAY INVISIBLE (-1375 1265);
FORCEPROP 2 LAST CDS_LIB mstr_misc
J 0
(-1300 1400);
PAINT ORANGE (-1300 1400);
DISPLAY INVISIBLE (-1300 1400);
FORCEPROP 0 LAST SEC 1
J 0
(-1375 1500);
DISPLAY 0.680851 (-1375 1500);
PAINT MONO (-1375 1500);
DISPLAY INVISIBLE (-1375 1500);
FORCEPROP 1 LAST PATH I105
J 0
(-1350 1500);
DISPLAY 0.978723 (-1350 1500);
PAINT ORANGE (-1350 1500);
DISPLAY INVISIBLE (-1350 1500);
FORCEPROP 2 LAST SEC_TYPE SH0201
J 0
(-1350 1550);
DISPLAY 1.021277 (-1350 1550);
PAINT ORANGE (-1350 1550);
DISPLAY INVISIBLE (-1350 1550);
FORCEADD CAP_A..1
(25 3275);
FORCEPROP 0 LAST STATUS NOPOP
J 0
(-200 3200);
DISPLAY 1.021277 (-200 3200);
PAINT ORANGE (-200 3200);
FORCEPROP 1 LAST VALUE 0.1UF
J 0
(75 3325);
DISPLAY 0.617021 (75 3325);
PAINT SKYBLUE (75 3325);
FORCEPROP 1 LAST PACK_TYPE 0402V
J 0
(75 3075);
DISPLAY 0.617021 (75 3075);
PAINT SKYBLUE (75 3075);
FORCEPROP 1 LAST PART_NUMBER A36096-030
J 0
(75 3125);
DISPLAY 0.617021 (75 3125);
PAINT BLUE (75 3125);
FORCEPROP 1 LAST TOLERANCE 10%
J 0
(75 3225);
DISPLAY 0.617021 (75 3225);
PAINT SKYBLUE (75 3225);
FORCEPROP 1 LAST VOLTAGE 16V
J 0
(75 3275);
DISPLAY 0.617021 (75 3275);
PAINT SKYBLUE (75 3275);
FORCEPROP 1 LAST LOCATION CT70
J 0
(150 3275);
DISPLAY 0.617021 (150 3275);
PAINT AQUA (150 3275);
FORCEPROP 1 LAST MATERIAL X7R
J 0
(75 3175);
DISPLAY 0.617021 (75 3175);
PAINT SKYBLUE (75 3175);
FORCEPROP 2 LAST ROOM PVCCIN_CPU0_PWR_VR
J 0
(75 3425);
DISPLAY 1.361702 (75 3425);
PAINT ORANGE (75 3425);
DISPLAY INVISIBLE (75 3425);
FORCEPROP 1 LAST PATH I106
J 0
(75 3425);
DISPLAY 0.978723 (75 3425);
PAINT WHITE (75 3425);
DISPLAY INVISIBLE (75 3425);
FORCEPROP 2 LAST CDS_LIB dev_discrete
J 0
(25 3275);
PAINT MONO (25 3275);
DISPLAY INVISIBLE (25 3275);
FORCEPROP 1 LASTPIN (25 3375) $PN 1
J 0
(35 3355);
DISPLAY 0.787234 (35 3355);
PAINT ORANGE (35 3355);
DISPLAY INVISIBLE (35 3355);
FORCEPROP 1 LASTPIN (25 3175) $PN 2
J 0
(35 3155);
DISPLAY 0.787234 (35 3155);
PAINT ORANGE (35 3155);
DISPLAY INVISIBLE (35 3155);
FORCEADD GND..1
(25 3025);
FORCEPROP 3 LASTPIN (25 3075) SIG_NAME GND\g
J 0
(35 3085);
DISPLAY 0.659574 (35 3085);
PAINT MONO (35 3085);
DISPLAY INVISIBLE (35 3085);
FORCEPROP 2 LAST ROOM PVCCIN_CPU0_PWR_VR
J 0
(-525 3100);
DISPLAY 1.936170 (-525 3100);
PAINT ORANGE (-525 3100);
DISPLAY INVISIBLE (-525 3100);
FORCEPROP 2 LAST BOM_COST PROC_VRD_VCCIN_CPU0
J 0
(-350 3100);
DISPLAY 1.446809 (-350 3100);
PAINT MONO (-350 3100);
DISPLAY INVISIBLE (-350 3100);
FORCEPROP 1 LAST SIZE 1B
J 0
(100 2975);
DISPLAY 1.723404 (100 2975);
PAINT GREEN (100 2975);
DISPLAY INVISIBLE (100 2975);
FORCEPROP 1 LAST VOLTAGE 0
J 0
(25 3025);
PAINT SKYBLUE (25 3025);
DISPLAY INVISIBLE (25 3025);
FORCEPROP 1 LAST PATH I107
J 0
(100 3025);
DISPLAY 0.872340 (100 3025);
PAINT AQUA (100 3025);
DISPLAY INVISIBLE (100 3025);
FORCEPROP 2 LAST CDS_LIB mstr_symbols
J 0
(25 3025);
PAINT MONO (25 3025);
DISPLAY INVISIBLE (25 3025);
FORCEPROP 1 LAST BODY_TYPE PLUMBING
J 0
(-20 2982);
DISPLAY 0.340426 (-20 2982);
PAINT GREEN (-20 2982);
DISPLAY INVISIBLE (-20 2982);
FORCEPROP 1 LAST HDL_POWER GND
J 0
(25 3175);
DISPLAY 1.723404 (25 3175);
PAINT GREEN (25 3175);
DISPLAY INVISIBLE (25 3175);
FORCEADD CAP..1
(1950 3800);
FORCEPROP 1 LAST PART_NUMBER A36096-046
J 0
(2000 3650);
DISPLAY 0.617021 (2000 3650);
PAINT BLUE (2000 3650);
FORCEPROP 1 LAST LOCATION CT71
J 0
(2000 3900);
DISPLAY 0.617021 (2000 3900);
PAINT AQUA (2000 3900);
FORCEPROP 1 LAST VOLTAGE 50V
J 0
(2000 3800);
DISPLAY 0.617021 (2000 3800);
PAINT SKYBLUE (2000 3800);
FORCEPROP 1 LAST VALUE 1000PF
J 0
(2000 3850);
DISPLAY 0.617021 (2000 3850);
PAINT SKYBLUE (2000 3850);
FORCEPROP 0 LAST STATUS NOPOP
J 0
(2075 3775);
DISPLAY 1.021277 (2075 3775);
PAINT ORANGE (2075 3775);
FORCEPROP 1 LAST PACK_TYPE 0402LF
J 0
(2000 3600);
DISPLAY 0.617021 (2000 3600);
PAINT SKYBLUE (2000 3600);
FORCEPROP 1 LAST TOLERANCE 10%
J 0
(2000 3750);
DISPLAY 0.617021 (2000 3750);
PAINT SKYBLUE (2000 3750);
FORCEPROP 1 LAST MATERIAL X7R
J 0
(2000 3700);
DISPLAY 0.617021 (2000 3700);
PAINT SKYBLUE (2000 3700);
FORCEPROP 0 LAST ROOM VDDQ_KLM_PWR_VR
J 0
(2000 4000);
DISPLAY 1.021277 (2000 4000);
PAINT ORANGE (2000 4000);
DISPLAY INVISIBLE (2000 4000);
FORCEPROP 1 LAST PATH I109
J 0
(2000 3950);
DISPLAY 0.978723 (2000 3950);
PAINT WHITE (2000 3950);
DISPLAY INVISIBLE (2000 3950);
FORCEPROP 2 LAST CDS_LIB mstr_discrete
J 0
(1950 3800);
PAINT MONO (1950 3800);
DISPLAY INVISIBLE (1950 3800);
FORCEPROP 1 LASTPIN (1950 3700) $PN 2
J 0
(1960 3680);
DISPLAY 0.787234 (1960 3680);
PAINT ORANGE (1960 3680);
DISPLAY INVISIBLE (1960 3680);
FORCEPROP 1 LASTPIN (1950 3900) $PN 1
J 0
(1960 3880);
DISPLAY 0.787234 (1960 3880);
PAINT ORANGE (1960 3880);
DISPLAY INVISIBLE (1960 3880);
FORCEADD GND..1
(1950 3575);
FORCEPROP 3 LASTPIN (1950 3625) SIG_NAME GND\g
J 0
(1960 3635);
DISPLAY 0.659574 (1960 3635);
PAINT MONO (1960 3635);
DISPLAY INVISIBLE (1960 3635);
FORCEPROP 2 LAST ROOM VDDQ_KLM_PWR_VR
J 0
(1375 3650);
DISPLAY 1.361702 (1375 3650);
PAINT ORANGE (1375 3650);
DISPLAY INVISIBLE (1375 3650);
FORCEPROP 1 LAST VOLTAGE 0
J 0
(1950 3575);
PAINT SKYBLUE (1950 3575);
DISPLAY INVISIBLE (1950 3575);
FORCEPROP 1 LAST SIZE 1B
J 0
(2025 3525);
DISPLAY 1.170213 (2025 3525);
PAINT AQUA (2025 3525);
DISPLAY INVISIBLE (2025 3525);
FORCEPROP 1 LAST PATH I110
J 0
(2025 3575);
DISPLAY 0.872340 (2025 3575);
PAINT AQUA (2025 3575);
DISPLAY INVISIBLE (2025 3575);
FORCEPROP 2 LAST CDS_LIB mstr_symbols
J 0
(1950 3575);
PAINT MONO (1950 3575);
DISPLAY INVISIBLE (1950 3575);
FORCEPROP 1 LAST BODY_TYPE PLUMBING
J 0
(1905 3532);
DISPLAY 0.340426 (1905 3532);
PAINT GREEN (1905 3532);
DISPLAY INVISIBLE (1905 3532);
FORCEPROP 1 LAST HDL_POWER GND
J 0
(1950 3725);
DISPLAY 1.170213 (1950 3725);
PAINT GREEN (1950 3725);
DISPLAY INVISIBLE (1950 3725);
FORCEADD SC2K2P50V3KX-GP..1
(2050 3325);
FORCEPROP 1 LAST VALUE SC2K2P50V3KX-GP
J 0
(2075 3275);
DISPLAY 0.617021 (2075 3275);
PAINT GREEN (2075 3275);
FORCEPROP 0 LAST STATUS NOPOP
J 0
(2075 3225);
DISPLAY 1.021277 (2075 3225);
PAINT ORANGE (2075 3225);
FORCEPROP 1 LAST LOCATION CT72
J 0
(2075 3355);
DISPLAY 0.617021 (2075 3355);
PAINT GREEN (2075 3355);
FORCEPROP 1 LAST PACK_TYPE SMD-BCG6
J 0
(2050 3325);
DISPLAY 0.617021 (2050 3325);
PAINT GREEN (2050 3325);
DISPLAY INVISIBLE (2050 3325);
FORCEPROP 1 LAST PART_NUMBER 78.22224.2BL
J 0
(2050 3325);
DISPLAY 0.617021 (2050 3325);
PAINT GREEN (2050 3325);
DISPLAY INVISIBLE (2050 3325);
FORCEPROP 1 LAST CDS_LMAN_SYM_OUTLINE -50,25,50,-25
J 0
(2050 3325);
DISPLAY 0.468085 (2050 3325);
PAINT GREEN (2050 3325);
DISPLAY INVISIBLE (2050 3325);
FORCEPROP 1 LAST PATH I111
J 0
(2050 3325);
DISPLAY 0.617021 (2050 3325);
PAINT GREEN (2050 3325);
DISPLAY INVISIBLE (2050 3325);
FORCEPROP 2 LAST CDS_LIB w_hdl
J 0
(2050 3325);
PAINT MONO (2050 3325);
DISPLAY INVISIBLE (2050 3325);
FORCEADD 3D01R5F-GP..1
R 4
(2050 3000);
FORCEPROP 1 LAST VALUE 3D01R5F-GP
J 0
(2075 3050);
DISPLAY 0.617021 (2075 3050);
PAINT GREEN (2075 3050);
FORCEPROP 1 LAST LOCATION RT48
J 0
(1925 2995);
DISPLAY 0.617021 (1925 2995);
PAINT GREEN (1925 2995);
FORCEPROP 0 LAST STATUS NOPOP
J 0
(2075 2975);
DISPLAY 1.021277 (2075 2975);
PAINT ORANGE (2075 2975);
FORCEPROP 1 LAST CDS_LMAN_SYM_OUTLINE -50,75,50,-75
R 2
J 0
(2050 3000);
DISPLAY 0.468085 (2050 3000);
PAINT GREEN (2050 3000);
DISPLAY INVISIBLE (2050 3000);
FORCEPROP 1 LAST PATH I112
R 2
J 0
(2050 3000);
DISPLAY 0.617021 (2050 3000);
PAINT GREEN (2050 3000);
DISPLAY INVISIBLE (2050 3000);
FORCEPROP 2 LAST CDS_LIB w_hdl
J 0
(2050 3000);
PAINT MONO (2050 3000);
DISPLAY INVISIBLE (2050 3000);
FORCEPROP 1 LAST PART_NUMBER 64.3R015.16L
R 2
J 0
(2050 3000);
DISPLAY 0.617021 (2050 3000);
PAINT GREEN (2050 3000);
DISPLAY INVISIBLE (2050 3000);
FORCEPROP 1 LAST PACK_TYPE SMD-RG5
R 2
J 0
(2050 3000);
DISPLAY 0.617021 (2050 3000);
PAINT GREEN (2050 3000);
DISPLAY INVISIBLE (2050 3000);
FORCEPROP 2 LASTPIN (2050 3125) SIG_NAME UN$212$3D01R5F-GP$I112$2
J 0
(2060 3135);
DISPLAY 0.659574 (2060 3135);
PAINT MONO (2060 3135);
DISPLAY INVISIBLE (2060 3135);
FORCEADD GND..1
(2050 2750);
FORCEPROP 3 LASTPIN (2050 2800) SIG_NAME GND\g
J 0
(2060 2810);
DISPLAY 0.659574 (2060 2810);
PAINT MONO (2060 2810);
DISPLAY INVISIBLE (2060 2810);
FORCEPROP 2 LAST ROOM PVCCIN_CPU0_PWR_VR
J 0
(1500 2825);
DISPLAY 1.936170 (1500 2825);
PAINT ORANGE (1500 2825);
DISPLAY INVISIBLE (1500 2825);
FORCEPROP 2 LAST BOM_COST PROC_VRD_VCCIN_CPU0
J 0
(1675 2825);
DISPLAY 1.446809 (1675 2825);
PAINT MONO (1675 2825);
DISPLAY INVISIBLE (1675 2825);
FORCEPROP 1 LAST VOLTAGE 0
J 0
(2050 2750);
PAINT SKYBLUE (2050 2750);
DISPLAY INVISIBLE (2050 2750);
FORCEPROP 1 LAST SIZE 1B
J 0
(2125 2700);
DISPLAY 1.723404 (2125 2700);
PAINT GREEN (2125 2700);
DISPLAY INVISIBLE (2125 2700);
FORCEPROP 1 LAST PATH I113
J 0
(2125 2750);
DISPLAY 0.872340 (2125 2750);
PAINT AQUA (2125 2750);
DISPLAY INVISIBLE (2125 2750);
FORCEPROP 2 LAST CDS_LIB mstr_symbols
J 0
(2050 2750);
PAINT MONO (2050 2750);
DISPLAY INVISIBLE (2050 2750);
FORCEPROP 1 LAST BODY_TYPE PLUMBING
J 0
(2005 2707);
DISPLAY 0.340426 (2005 2707);
PAINT GREEN (2005 2707);
DISPLAY INVISIBLE (2005 2707);
FORCEPROP 1 LAST HDL_POWER GND
J 0
(2050 2900);
DISPLAY 1.723404 (2050 2900);
PAINT GREEN (2050 2900);
DISPLAY INVISIBLE (2050 2900);
FORCEADD RES..1
(-950 3575);
FORCEPROP 1 LAST PACK_TYPE 0402
J 0
(-850 3425);
DISPLAY 0.617021 (-850 3425);
PAINT SKYBLUE (-850 3425);
FORCEPROP 1 LAST PART_NUMBER G21497-005
J 0
(-1050 3525);
DISPLAY 0.617021 (-1050 3525);
PAINT BLUE (-1050 3525);
FORCEPROP 1 LAST LOCATION RT47
J 0
(-1000 3600);
DISPLAY 0.617021 (-1000 3600);
PAINT AQUA (-1000 3600);
FORCEPROP 1 LAST WATTAGE 1/16W
J 2
(-975 3425);
DISPLAY 0.617021 (-975 3425);
PAINT SKYBLUE (-975 3425);
FORCEPROP 1 LAST MATERIAL CHIP
J 0
(-950 3425);
DISPLAY 0.617021 (-950 3425);
PAINT SKYBLUE (-950 3425);
FORCEPROP 1 LAST TOLERANCE 5%
J 0
(-950 3475);
DISPLAY 0.617021 (-950 3475);
PAINT SKYBLUE (-950 3475);
FORCEPROP 1 LAST VALUE 0.0
J 2
(-975 3475);
DISPLAY 0.617021 (-975 3475);
PAINT SKYBLUE (-975 3475);
FORCEPROP 2 LAST BOM_COST DEBUG
J 0
(-1000 3775);
DISPLAY 1.021277 (-1000 3775);
PAINT ORANGE (-1000 3775);
DISPLAY INVISIBLE (-1000 3775);
FORCEPROP 2 LAST ROOM BMC_DEBUG_HEADER
J 0
(-1000 3725);
DISPLAY 1.021277 (-1000 3725);
PAINT ORANGE (-1000 3725);
DISPLAY INVISIBLE (-1000 3725);
FORCEPROP 1 LAST PATH I114
J 0
(-1000 3725);
DISPLAY 0.978723 (-1000 3725);
PAINT WHITE (-1000 3725);
DISPLAY INVISIBLE (-1000 3725);
FORCEPROP 2 LAST CDS_LIB mstr_discrete
J 0
(-950 3575);
PAINT MONO (-950 3575);
DISPLAY INVISIBLE (-950 3575);
FORCEPROP 1 LASTPIN (-1050 3575) $PN 1
J 0
(-1038 3587);
DISPLAY 0.787234 (-1038 3587);
PAINT ORANGE (-1038 3587);
DISPLAY INVISIBLE (-1038 3587);
FORCEPROP 1 LASTPIN (-850 3575) $PN 2
J 0
(-888 3587);
DISPLAY 0.787234 (-888 3587);
PAINT ORANGE (-888 3587);
DISPLAY INVISIBLE (-888 3587);
FORCEADD GND..1
(3375 2050);
FORCEPROP 3 LASTPIN (3375 2100) SIG_NAME GND\g
J 0
(3385 2110);
DISPLAY 0.659574 (3385 2110);
PAINT MONO (3385 2110);
DISPLAY INVISIBLE (3385 2110);
FORCEPROP 1 LAST SIZE 1B
J 0
(3450 2000);
DISPLAY 0.638298 (3450 2000);
PAINT GREEN (3450 2000);
DISPLAY INVISIBLE (3450 2000);
FORCEPROP 2 LAST BOM_COST PROC_VRD_PVCCIO_CPU0
J 0
(2875 2125);
DISPLAY 0.723404 (2875 2125);
PAINT ORANGE (2875 2125);
DISPLAY INVISIBLE (2875 2125);
FORCEPROP 2 LAST ROOM PVCCIO_CPU0
J 0
(3075 2125);
DISPLAY 0.723404 (3075 2125);
PAINT ORANGE (3075 2125);
DISPLAY INVISIBLE (3075 2125);
FORCEPROP 1 LAST VOLTAGE 0
J 0
(3375 2050);
DISPLAY 0.723404 (3375 2050);
PAINT SKYBLUE (3375 2050);
DISPLAY INVISIBLE (3375 2050);
FORCEPROP 2 LAST CDS_LIB mstr_symbols
J 0
(3375 2050);
DISPLAY 0.723404 (3375 2050);
PAINT ORANGE (3375 2050);
DISPLAY INVISIBLE (3375 2050);
FORCEPROP 1 LAST PATH I13
J 0
(3450 2050);
DISPLAY 0.872340 (3450 2050);
PAINT AQUA (3450 2050);
DISPLAY INVISIBLE (3450 2050);
FORCEPROP 1 LAST BODY_TYPE PLUMBING
J 0
(3330 2007);
DISPLAY 0.340426 (3330 2007);
PAINT GREEN (3330 2007);
DISPLAY INVISIBLE (3330 2007);
FORCEPROP 1 LAST HDL_POWER GND
J 0
(3375 2200);
DISPLAY 0.638298 (3375 2200);
PAINT GREEN (3375 2200);
DISPLAY INVISIBLE (3375 2200);
FORCEADD CAPP..1
R 2
(3375 2400);
FORCEPROP 1 LASTPIN (3375 2300) $PN 2
J 2
(3365 2285);
DISPLAY 0.617021 (3365 2285);
PAINT WHITE (3365 2285);
FORCEPROP 1 LAST PART_NUMBER 699013-049
R 1
J 2
(3450 2525);
DISPLAY 0.617021 (3450 2525);
PAINT BLUE (3450 2525);
FORCEPROP 1 LASTPIN (3375 2500) $PN 1
J 2
(3365 2485);
DISPLAY 0.617021 (3365 2485);
PAINT WHITE (3365 2485);
FORCEPROP 1 LAST LOCATION C3N38
J 2
(3325 2500);
DISPLAY 0.617021 (3325 2500);
PAINT AQUA (3325 2500);
FORCEPROP 1 LAST VALUE 470UF
J 2
(3325 2450);
DISPLAY 0.617021 (3325 2450);
PAINT SKYBLUE (3325 2450);
FORCEPROP 1 LAST TOLERANCE 20%
J 2
(3325 2400);
DISPLAY 0.617021 (3325 2400);
PAINT SKYBLUE (3325 2400);
FORCEPROP 1 LAST VOLTAGE 2.5V
J 2
(3325 2350);
DISPLAY 0.617021 (3325 2350);
PAINT SKYBLUE (3325 2350);
FORCEPROP 1 LAST MATERIAL ALUM
J 2
(3325 2300);
DISPLAY 0.617021 (3325 2300);
PAINT SKYBLUE (3325 2300);
FORCEPROP 1 LAST PACK_TYPE 3018
J 2
(3325 2250);
DISPLAY 0.617021 (3325 2250);
PAINT SKYBLUE (3325 2250);
FORCEPROP 2 LAST CDS_LOCATION C3N38
J 2
(3325 2500);
DISPLAY 0.617021 (3325 2500);
PAINT AQUA (3325 2500);
DISPLAY INVISIBLE (3325 2500);
FORCEPROP 2 LAST CDS_LIB mstr_discrete
J 0
(3375 2400);
PAINT ORANGE (3375 2400);
DISPLAY INVISIBLE (3375 2400);
FORCEPROP 2 LAST BOM_COST PROC_VRD_PVCCIO_CPU0
J 2
(3325 2550);
PAINT MONO (3325 2550);
DISPLAY INVISIBLE (3325 2550);
FORCEPROP 1 LAST PATH I16
J 2
(3325 2550);
DISPLAY 0.978723 (3325 2550);
PAINT ORANGE (3325 2550);
DISPLAY INVISIBLE (3325 2550);
FORCEPROP 2 LAST ROOM PVCCIO_CPU0
J 2
(3325 2525);
PAINT MONO (3325 2525);
DISPLAY INVISIBLE (3325 2525);
FORCEPROP 2 LAST CDS_SEC 1
J 0
(3325 2600);
PAINT MONO (3325 2600);
DISPLAY INVISIBLE (3325 2600);
FORCEPROP 2 LAST $SEC 1
J 0
(3385 3040);
DISPLAY 0.680851 (3385 3040);
PAINT MONO (3385 3040);
DISPLAY INVISIBLE (3385 3040);
FORCEADD CAPP..1
R 2
(2950 2400);
FORCEPROP 1 LAST LOCATION C3N26
J 2
(2900 2500);
DISPLAY 0.617021 (2900 2500);
PAINT AQUA (2900 2500);
FORCEPROP 1 LAST VOLTAGE 2.5V
J 2
(2900 2350);
DISPLAY 0.617021 (2900 2350);
PAINT SKYBLUE (2900 2350);
FORCEPROP 1 LAST PACK_TYPE 3018
J 2
(2900 2250);
DISPLAY 0.617021 (2900 2250);
PAINT SKYBLUE (2900 2250);
FORCEPROP 1 LAST TOLERANCE 20%
J 2
(2900 2400);
DISPLAY 0.617021 (2900 2400);
PAINT SKYBLUE (2900 2400);
FORCEPROP 1 LASTPIN (2950 2500) $PN 1
J 2
(2940 2485);
DISPLAY 0.617021 (2940 2485);
PAINT WHITE (2940 2485);
FORCEPROP 1 LAST VALUE 470UF
J 2
(2900 2450);
DISPLAY 0.617021 (2900 2450);
PAINT SKYBLUE (2900 2450);
FORCEPROP 1 LAST PART_NUMBER 699013-049
R 1
J 2
(3025 2525);
DISPLAY 0.617021 (3025 2525);
PAINT BLUE (3025 2525);
FORCEPROP 1 LASTPIN (2950 2300) $PN 2
J 2
(2940 2285);
DISPLAY 0.617021 (2940 2285);
PAINT WHITE (2940 2285);
FORCEPROP 1 LAST MATERIAL ALUM
J 2
(2900 2300);
DISPLAY 0.617021 (2900 2300);
PAINT SKYBLUE (2900 2300);
FORCEPROP 2 LAST CDS_LOCATION C3N26
J 2
(2900 2500);
DISPLAY 0.617021 (2900 2500);
PAINT AQUA (2900 2500);
DISPLAY INVISIBLE (2900 2500);
FORCEPROP 2 LAST CDS_LIB mstr_discrete
J 0
(2950 2400);
PAINT ORANGE (2950 2400);
DISPLAY INVISIBLE (2950 2400);
FORCEPROP 2 LAST BOM_COST PROC_VRD_PVCCIO_CPU0
J 2
(2900 2550);
PAINT MONO (2900 2550);
DISPLAY INVISIBLE (2900 2550);
FORCEPROP 1 LAST PATH I17
J 2
(2900 2550);
DISPLAY 0.978723 (2900 2550);
PAINT ORANGE (2900 2550);
DISPLAY INVISIBLE (2900 2550);
FORCEPROP 2 LAST ROOM PVCCIO_CPU0
J 2
(2900 2525);
PAINT MONO (2900 2525);
DISPLAY INVISIBLE (2900 2525);
FORCEPROP 2 LAST CDS_SEC 1
J 0
(2900 2600);
PAINT MONO (2900 2600);
DISPLAY INVISIBLE (2900 2600);
FORCEPROP 2 LAST $SEC 1
J 0
(3285 3040);
DISPLAY 0.680851 (3285 3040);
PAINT MONO (3285 3040);
DISPLAY INVISIBLE (3285 3040);
FORCEADD CAPP..1
R 2
(2550 2400);
FORCEPROP 1 LAST PACK_TYPE 3018
J 2
(2500 2250);
DISPLAY 0.617021 (2500 2250);
PAINT SKYBLUE (2500 2250);
FORCEPROP 1 LASTPIN (2550 2300) $PN 2
J 2
(2540 2285);
DISPLAY 0.617021 (2540 2285);
PAINT WHITE (2540 2285);
FORCEPROP 1 LAST MATERIAL ALUM
J 2
(2500 2300);
DISPLAY 0.617021 (2500 2300);
PAINT SKYBLUE (2500 2300);
FORCEPROP 1 LAST TOLERANCE 20%
J 2
(2500 2400);
DISPLAY 0.617021 (2500 2400);
PAINT SKYBLUE (2500 2400);
FORCEPROP 1 LAST VOLTAGE 2.5V
J 2
(2500 2350);
DISPLAY 0.617021 (2500 2350);
PAINT SKYBLUE (2500 2350);
FORCEPROP 1 LASTPIN (2550 2500) $PN 1
J 2
(2540 2485);
DISPLAY 0.617021 (2540 2485);
PAINT WHITE (2540 2485);
FORCEPROP 1 LAST LOCATION C3N35
J 2
(2500 2500);
DISPLAY 0.617021 (2500 2500);
PAINT AQUA (2500 2500);
FORCEPROP 1 LAST PART_NUMBER 699013-049
R 1
J 2
(2625 2525);
DISPLAY 0.617021 (2625 2525);
PAINT BLUE (2625 2525);
FORCEPROP 1 LAST VALUE 470UF
J 2
(2500 2450);
DISPLAY 0.617021 (2500 2450);
PAINT SKYBLUE (2500 2450);
FORCEPROP 2 LAST CDS_LIB mstr_discrete
J 0
(2550 2400);
PAINT ORANGE (2550 2400);
DISPLAY INVISIBLE (2550 2400);
FORCEPROP 2 LAST CDS_LOCATION C3N35
J 2
(2500 2500);
DISPLAY 0.617021 (2500 2500);
PAINT AQUA (2500 2500);
DISPLAY INVISIBLE (2500 2500);
FORCEPROP 2 LAST BOM_COST PROC_VRD_PVCCIO_CPU0
J 2
(2500 2550);
PAINT MONO (2500 2550);
DISPLAY INVISIBLE (2500 2550);
FORCEPROP 1 LAST PATH I18
J 2
(2500 2550);
DISPLAY 0.978723 (2500 2550);
PAINT ORANGE (2500 2550);
DISPLAY INVISIBLE (2500 2550);
FORCEPROP 2 LAST ROOM PVCCIO_CPU0
J 2
(2500 2525);
PAINT MONO (2500 2525);
DISPLAY INVISIBLE (2500 2525);
FORCEPROP 2 LAST CDS_SEC 1
J 0
(2500 2600);
PAINT MONO (2500 2600);
DISPLAY INVISIBLE (2500 2600);
FORCEPROP 2 LAST $SEC 1
J 0
(3210 3040);
DISPLAY 0.680851 (3210 3040);
PAINT MONO (3210 3040);
DISPLAY INVISIBLE (3210 3040);
FORCEADD OFFPAGE..2
(2725 4650);
FORCEPROP 2 LAST $XR0 211 
J 0
(2914 4650);
DISPLAY 0.638298 (2914 4650);
PAINT MONO (2914 4650);
FORCEPROP 2 LAST ROOM PVCCIO_CPU0
J 0
(2325 4725);
DISPLAY 3.127660 (2325 4725);
PAINT WHITE (2325 4725);
DISPLAY INVISIBLE (2325 4725);
FORCEPROP 2 LAST CDS_LIB mstr_standard
J 0
(2725 4650);
DISPLAY 1.617021 (2725 4650);
PAINT ORANGE (2725 4650);
DISPLAY INVISIBLE (2725 4650);
FORCEPROP 2 LAST BOM_COST PROC_VRD_PVCCIO_CPU0
J 0
(2925 4700);
DISPLAY 2.340426 (2925 4700);
PAINT WHITE (2925 4700);
DISPLAY INVISIBLE (2925 4700);
FORCEPROP 2 LAST PATH I19
J 0
(3175 4700);
DISPLAY 1.021277 (3175 4700);
PAINT ORANGE (3175 4700);
DISPLAY INVISIBLE (3175 4700);
FORCEPROP 1 LAST OFFPAGE TRUE
J 0
(3050 4525);
PAINT GREEN (3050 4525);
DISPLAY INVISIBLE (3050 4525);
FORCEPROP 1 LAST COMMENT_BODY TRUE
J 0
(2680 4555);
DISPLAY 2.787234 (2680 4555);
PAINT PEACH (2680 4555);
DISPLAY INVISIBLE (2680 4555);
FORCEADD OFFPAGE..2
(2675 4325);
FORCEPROP 2 LAST $XR0 211 
J 0
(2864 4325);
DISPLAY 0.638298 (2864 4325);
PAINT MONO (2864 4325);
FORCEPROP 2 LAST ROOM PVCCIO_CPU0
J 0
(2275 4400);
DISPLAY 3.127660 (2275 4400);
PAINT WHITE (2275 4400);
DISPLAY INVISIBLE (2275 4400);
FORCEPROP 2 LAST CDS_LIB mstr_standard
J 0
(2675 4325);
DISPLAY 1.617021 (2675 4325);
PAINT ORANGE (2675 4325);
DISPLAY INVISIBLE (2675 4325);
FORCEPROP 2 LAST PATH I20
J 0
(2850 4400);
DISPLAY 1.021277 (2850 4400);
PAINT ORANGE (2850 4400);
DISPLAY INVISIBLE (2850 4400);
FORCEPROP 2 LAST BOM_COST PROC_VRD_PVCCIO_CPU0
J 0
(2875 4375);
DISPLAY 2.340426 (2875 4375);
PAINT WHITE (2875 4375);
DISPLAY INVISIBLE (2875 4375);
FORCEPROP 1 LAST OFFPAGE TRUE
J 0
(3000 4200);
PAINT GREEN (3000 4200);
DISPLAY INVISIBLE (3000 4200);
FORCEPROP 1 LAST COMMENT_BODY TRUE
J 0
(2630 4230);
DISPLAY 2.787234 (2630 4230);
PAINT PEACH (2630 4230);
DISPLAY INVISIBLE (2630 4230);
FORCEADD OFFPAGE..2
(2450 3975);
FORCEPROP 2 LAST $XR0 211 
J 0
(2639 3975);
DISPLAY 0.638298 (2639 3975);
PAINT MONO (2639 3975);
FORCEPROP 2 LAST BOM_COST PROC_VRD_PVCCIO_CPU0
J 0
(2650 4025);
DISPLAY 2.340426 (2650 4025);
PAINT WHITE (2650 4025);
DISPLAY INVISIBLE (2650 4025);
FORCEPROP 2 LAST PATH I21
J 0
(2775 4025);
DISPLAY 1.021277 (2775 4025);
PAINT ORANGE (2775 4025);
DISPLAY INVISIBLE (2775 4025);
FORCEPROP 2 LAST ROOM PVCCIO_CPU0
J 0
(2050 4050);
DISPLAY 3.127660 (2050 4050);
PAINT WHITE (2050 4050);
DISPLAY INVISIBLE (2050 4050);
FORCEPROP 2 LAST CDS_LIB mstr_standard
J 0
(2450 3975);
DISPLAY 1.617021 (2450 3975);
PAINT ORANGE (2450 3975);
DISPLAY INVISIBLE (2450 3975);
FORCEPROP 1 LAST OFFPAGE TRUE
J 0
(2775 3850);
PAINT GREEN (2775 3850);
DISPLAY INVISIBLE (2775 3850);
FORCEPROP 1 LAST COMMENT_BODY TRUE
J 0
(2405 3880);
DISPLAY 2.787234 (2405 3880);
PAINT PEACH (2405 3880);
DISPLAY INVISIBLE (2405 3880);
FORCEADD PVCCIO_CPU0..1
(3600 3600);
FORCEPROP 3 LASTPIN (3600 3550) SIG_NAME PVCCIO_CPU0\g
J 0
(3610 3560);
DISPLAY 0.659574 (3610 3560);
PAINT MONO (3610 3560);
DISPLAY INVISIBLE (3610 3560);
FORCEPROP 1 LAST VOLTAGE 1.1V
J 0
(3555 3557);
DISPLAY 0.340426 (3555 3557);
PAINT SKYBLUE (3555 3557);
DISPLAY INVISIBLE (3555 3557);
FORCEPROP 2 LAST CDS_LIB mstr_symbols
J 0
(3600 3600);
PAINT ORANGE (3600 3600);
DISPLAY INVISIBLE (3600 3600);
FORCEPROP 1 LAST PATH I22
J 0
(3650 3625);
DISPLAY 0.872340 (3650 3625);
PAINT AQUA (3650 3625);
DISPLAY INVISIBLE (3650 3625);
FORCEPROP 1 LAST BODY_TYPE PLUMBING
J 0
(3555 3557);
DISPLAY 0.340426 (3555 3557);
PAINT GREEN (3555 3557);
DISPLAY INVISIBLE (3555 3557);
FORCEPROP 1 LAST HDL_POWER PVCCIO_CPU0
J 1
(3600 3650);
DISPLAY 0.872340 (3600 3650);
PAINT GREEN (3600 3650);
DISPLAY INVISIBLE (3600 3650);
FORCEADD CAP_A..1
(2925 3275);
FORCEPROP 1 LAST LOCATION C7C6
J 0
(2975 3375);
DISPLAY 0.617021 (2975 3375);
PAINT AQUA (2975 3375);
FORCEPROP 1 LASTPIN (2925 3175) $PN 2
J 0
(2935 3155);
DISPLAY 0.617021 (2935 3155);
PAINT WHITE (2935 3155);
FORCEPROP 1 LAST MATERIAL X6S
J 0
(2975 3175);
DISPLAY 0.617021 (2975 3175);
PAINT SKYBLUE (2975 3175);
FORCEPROP 1 LAST VOLTAGE 4V
J 0
(2975 3275);
DISPLAY 0.617021 (2975 3275);
PAINT SKYBLUE (2975 3275);
FORCEPROP 1 LAST TOLERANCE 20%
J 0
(2975 3225);
DISPLAY 0.617021 (2975 3225);
PAINT SKYBLUE (2975 3225);
FORCEPROP 1 LASTPIN (2925 3375) $PN 1
J 0
(2935 3355);
DISPLAY 0.617021 (2935 3355);
PAINT WHITE (2935 3355);
FORCEPROP 1 LAST PACK_TYPE 0603V
J 0
(2975 3075);
DISPLAY 0.617021 (2975 3075);
PAINT SKYBLUE (2975 3075);
FORCEPROP 1 LAST VALUE 22.0UF
J 0
(2975 3325);
DISPLAY 0.617021 (2975 3325);
PAINT SKYBLUE (2975 3325);
FORCEPROP 1 LAST PART_NUMBER E15431-004
J 0
(2975 3125);
DISPLAY 0.617021 (2975 3125);
PAINT BLUE (2975 3125);
FORCEPROP 2 LAST CDS_LIB dev_discrete
J 0
(2925 3275);
PAINT ORANGE (2925 3275);
DISPLAY INVISIBLE (2925 3275);
FORCEPROP 2 LAST ROOM PVCCIO_CPU0
J 0
(2975 3425);
DISPLAY 2.340426 (2975 3425);
PAINT WHITE (2975 3425);
DISPLAY INVISIBLE (2975 3425);
FORCEPROP 1 LAST PATH I23
J 0
(2975 3425);
DISPLAY 0.978723 (2975 3425);
PAINT WHITE (2975 3425);
DISPLAY INVISIBLE (2975 3425);
FORCEPROP 2 LAST SEC 1
J 0
(2980 3475);
DISPLAY 1.106383 (2980 3475);
PAINT MONO (2980 3475);
DISPLAY INVISIBLE (2980 3475);
FORCEPROP 2 LAST SEC_TYPE 0603V
J 0
(2980 3475);
DISPLAY 1.659574 (2980 3475);
PAINT ORANGE (2980 3475);
DISPLAY INVISIBLE (2980 3475);
FORCEPROP 2 LAST CDS_SEC 1
J 0
(2975 3425);
PAINT ORANGE (2975 3425);
DISPLAY INVISIBLE (2975 3425);
FORCEPROP 2 LAST BOM_COST PROC_VRD_PVCCIO_CPU0
J 0
(2975 3425);
DISPLAY 2.340426 (2975 3425);
PAINT WHITE (2975 3425);
DISPLAY INVISIBLE (2975 3425);
FORCEPROP 2 LAST CDS_LOCATION C7C6
J 0
(2975 3375);
DISPLAY 0.617021 (2975 3375);
PAINT AQUA (2975 3375);
DISPLAY INVISIBLE (2975 3375);
FORCEADD GND..1
(2925 2950);
FORCEPROP 3 LASTPIN (2925 3000) SIG_NAME GND\g
J 0
(2935 3010);
DISPLAY 0.659574 (2935 3010);
PAINT MONO (2935 3010);
DISPLAY INVISIBLE (2935 3010);
FORCEPROP 1 LAST VOLTAGE 0.0V
J 0
(2880 2907);
DISPLAY 0.340426 (2880 2907);
PAINT SKYBLUE (2880 2907);
DISPLAY INVISIBLE (2880 2907);
FORCEPROP 2 LAST CDS_LIB mstr_symbols
J 0
(2925 2950);
DISPLAY 1.617021 (2925 2950);
PAINT ORANGE (2925 2950);
DISPLAY INVISIBLE (2925 2950);
FORCEPROP 1 LAST PATH I24
J 0
(3000 2950);
DISPLAY 0.872340 (3000 2950);
PAINT AQUA (3000 2950);
DISPLAY INVISIBLE (3000 2950);
FORCEPROP 1 LAST SIZE 1B
J 0
(3000 2900);
DISPLAY 2.787234 (3000 2900);
PAINT GREEN (3000 2900);
DISPLAY INVISIBLE (3000 2900);
FORCEPROP 2 LAST BOM_COST PROC_VRD_PVCCIO_CPU0
J 0
(2550 3025);
DISPLAY 2.340426 (2550 3025);
PAINT WHITE (2550 3025);
DISPLAY INVISIBLE (2550 3025);
FORCEPROP 2 LAST ROOM PVCCIO_CPU0
J 0
(2375 3025);
DISPLAY 3.127660 (2375 3025);
PAINT WHITE (2375 3025);
DISPLAY INVISIBLE (2375 3025);
FORCEPROP 1 LAST BODY_TYPE PLUMBING
J 0
(2880 2907);
DISPLAY 0.340426 (2880 2907);
PAINT GREEN (2880 2907);
DISPLAY INVISIBLE (2880 2907);
FORCEPROP 1 LAST HDL_POWER GND
J 0
(2925 3100);
DISPLAY 2.787234 (2925 3100);
PAINT GREEN (2925 3100);
DISPLAY INVISIBLE (2925 3100);
FORCEADD INDUCTOR..1
(2475 3475);
FORCEPROP 1 LAST PART_NUMBER D92183-021
J 0
(2375 3575);
DISPLAY 0.617021 (2375 3575);
PAINT BLUE (2375 3575);
FORCEPROP 1 LAST LOCATION L7C2
J 0
(2375 3525);
DISPLAY 0.617021 (2375 3525);
PAINT AQUA (2375 3525);
FORCEPROP 1 LAST VALUE 150NH
J 2
(2470 3390);
DISPLAY 0.617021 (2470 3390);
PAINT SKYBLUE (2470 3390);
FORCEPROP 1 LAST PACK_TYPE SM
J 0
(2440 3340);
DISPLAY 0.617021 (2440 3340);
PAINT SKYBLUE (2440 3340);
FORCEPROP 1 LAST MATERIAL IND
J 0
(2490 3390);
DISPLAY 0.617021 (2490 3390);
PAINT SKYBLUE (2490 3390);
FORCEPROP 2 LAST CDS_LOCATION L7C2
J 0
(2375 3525);
DISPLAY 0.617021 (2375 3525);
PAINT AQUA (2375 3525);
DISPLAY INVISIBLE (2375 3525);
FORCEPROP 1 LASTPIN (2375 3475) $PN 1
J 0
(2375 3485);
DISPLAY 0.702128 (2375 3485);
PAINT WHITE (2375 3485);
DISPLAY INVISIBLE (2375 3485);
FORCEPROP 2 LAST CDS_LIB mstr_discrete
J 0
(2475 3475);
PAINT ORANGE (2475 3475);
DISPLAY INVISIBLE (2475 3475);
FORCEPROP 1 LASTPIN (2575 3475) $PN 2
J 2
(2585 3485);
DISPLAY 0.702128 (2585 3485);
PAINT WHITE (2585 3485);
DISPLAY INVISIBLE (2585 3485);
FORCEPROP 2 LAST ROOM PVCCIO_CPU0
J 0
(2375 3575);
DISPLAY 2.212766 (2375 3575);
PAINT WHITE (2375 3575);
DISPLAY INVISIBLE (2375 3575);
FORCEPROP 2 LAST CDS_SEC 1
J 0
(2375 3675);
PAINT MONO (2375 3675);
DISPLAY INVISIBLE (2375 3675);
FORCEPROP 2 LAST $SEC 1
J 0
(2375 3675);
PAINT MONO (2375 3675);
DISPLAY INVISIBLE (2375 3675);
FORCEPROP 1 LAST PATH I25
J 0
(2375 3625);
DISPLAY 0.978723 (2375 3625);
PAINT ORANGE (2375 3625);
DISPLAY INVISIBLE (2375 3625);
FORCEADD GND..1
(1475 3025);
FORCEPROP 3 LASTPIN (1475 3075) SIG_NAME GND\g
J 0
(1485 3085);
DISPLAY 0.659574 (1485 3085);
PAINT MONO (1485 3085);
DISPLAY INVISIBLE (1485 3085);
FORCEPROP 2 LAST ROOM PVCCIO_CPU0
J 0
(925 3100);
DISPLAY 3.127660 (925 3100);
PAINT WHITE (925 3100);
DISPLAY INVISIBLE (925 3100);
FORCEPROP 1 LAST VOLTAGE 0.0V
J 0
(1430 2982);
DISPLAY 0.340426 (1430 2982);
PAINT SKYBLUE (1430 2982);
DISPLAY INVISIBLE (1430 2982);
FORCEPROP 1 LAST PATH I29
J 0
(1550 3025);
DISPLAY 0.872340 (1550 3025);
PAINT AQUA (1550 3025);
DISPLAY INVISIBLE (1550 3025);
FORCEPROP 1 LAST SIZE 1B
J 0
(1550 2975);
DISPLAY 2.787234 (1550 2975);
PAINT GREEN (1550 2975);
DISPLAY INVISIBLE (1550 2975);
FORCEPROP 2 LAST CDS_LIB mstr_symbols
J 0
(1475 3025);
DISPLAY 1.617021 (1475 3025);
PAINT ORANGE (1475 3025);
DISPLAY INVISIBLE (1475 3025);
FORCEPROP 2 LAST BOM_COST PROC_VRD_PVCCIO_CPU0
J 0
(1100 3100);
DISPLAY 2.340426 (1100 3100);
PAINT WHITE (1100 3100);
DISPLAY INVISIBLE (1100 3100);
FORCEPROP 1 LAST BODY_TYPE PLUMBING
J 0
(1430 2982);
DISPLAY 0.340426 (1430 2982);
PAINT GREEN (1430 2982);
DISPLAY INVISIBLE (1430 2982);
FORCEPROP 1 LAST HDL_POWER GND
J 0
(1475 3175);
DISPLAY 2.787234 (1475 3175);
PAINT GREEN (1475 3175);
DISPLAY INVISIBLE (1475 3175);
FORCEADD RES..1
(-1725 4575);
FORCEPROP 1 LAST WATTAGE 1/16W
J 2
(-1700 4400);
DISPLAY 0.617021 (-1700 4400);
PAINT SKYBLUE (-1700 4400);
FORCEPROP 1 LAST PART_NUMBER G21796-090
J 0
(-1850 4500);
DISPLAY 0.617021 (-1850 4500);
PAINT BLUE (-1850 4500);
FORCEPROP 1 LAST PACK_TYPE 0402
J 0
(-1675 4450);
DISPLAY 0.617021 (-1675 4450);
PAINT SKYBLUE (-1675 4450);
FORCEPROP 1 LAST TOLERANCE 1%
J 0
(-1775 4450);
DISPLAY 0.617021 (-1775 4450);
PAINT SKYBLUE (-1775 4450);
FORCEPROP 1 LASTPIN (-1625 4575) $PN 2
J 0
(-1663 4587);
DISPLAY 0.617021 (-1663 4587);
PAINT WHITE (-1663 4587);
FORCEPROP 1 LASTPIN (-1825 4575) $PN 1
J 0
(-1813 4587);
DISPLAY 0.617021 (-1813 4587);
PAINT WHITE (-1813 4587);
FORCEPROP 1 LAST LOCATION R3N7
J 0
(-1775 4625);
DISPLAY 0.617021 (-1775 4625);
PAINT AQUA (-1775 4625);
FORCEPROP 1 LAST MATERIAL CHIP
J 0
(-1650 4400);
DISPLAY 0.617021 (-1650 4400);
PAINT SKYBLUE (-1650 4400);
FORCEPROP 1 LAST VALUE 1.0
J 2
(-1825 4450);
DISPLAY 0.617021 (-1825 4450);
PAINT SKYBLUE (-1825 4450);
FORCEPROP 2 LAST CDS_LIB mstr_discrete
J 0
(-1725 4575);
DISPLAY 1.617021 (-1725 4575);
PAINT ORANGE (-1725 4575);
DISPLAY INVISIBLE (-1725 4575);
FORCEPROP 2 LAST SEC_TYPE 0402
J 0
(-1775 4775);
DISPLAY 1.659574 (-1775 4775);
PAINT ORANGE (-1775 4775);
DISPLAY INVISIBLE (-1775 4775);
FORCEPROP 2 LAST SEC 1
J 0
(-1775 4775);
DISPLAY 1.106383 (-1775 4775);
PAINT MONO (-1775 4775);
DISPLAY INVISIBLE (-1775 4775);
FORCEPROP 2 LAST CDS_LOCATION R3N7
J 0
(-1775 4625);
DISPLAY 0.617021 (-1775 4625);
PAINT AQUA (-1775 4625);
DISPLAY INVISIBLE (-1775 4625);
FORCEPROP 1 LAST PATH I32
J 0
(-1775 4725);
DISPLAY 0.978723 (-1775 4725);
PAINT WHITE (-1775 4725);
DISPLAY INVISIBLE (-1775 4725);
FORCEPROP 2 LAST ROOM PVCCIO_CPU0
J 0
(-1775 4675);
DISPLAY 2.212766 (-1775 4675);
PAINT WHITE (-1775 4675);
DISPLAY INVISIBLE (-1775 4675);
FORCEADD CAP..1
(-1275 4050);
FORCEPROP 1 LAST MATERIAL X7R
J 0
(-1225 3950);
DISPLAY 0.617021 (-1225 3950);
PAINT SKYBLUE (-1225 3950);
FORCEPROP 1 LAST PART_NUMBER A36096-155
J 0
(-1225 3900);
DISPLAY 0.617021 (-1225 3900);
PAINT BLUE (-1225 3900);
FORCEPROP 1 LAST TOLERANCE 10%
J 0
(-1225 4000);
DISPLAY 0.617021 (-1225 4000);
PAINT SKYBLUE (-1225 4000);
FORCEPROP 1 LAST PACK_TYPE 0402
J 0
(-1225 3850);
DISPLAY 0.617021 (-1225 3850);
PAINT SKYBLUE (-1225 3850);
FORCEPROP 1 LAST VOLTAGE 16V
J 0
(-1225 4050);
DISPLAY 0.617021 (-1225 4050);
PAINT SKYBLUE (-1225 4050);
FORCEPROP 1 LASTPIN (-1275 3950) $PN 2
J 0
(-1265 3930);
DISPLAY 0.617021 (-1265 3930);
PAINT WHITE (-1265 3930);
FORCEPROP 1 LAST LOCATION C7C18
J 0
(-1225 4150);
DISPLAY 0.617021 (-1225 4150);
PAINT AQUA (-1225 4150);
FORCEPROP 1 LAST VALUE 0.22UF
J 0
(-1225 4100);
DISPLAY 0.617021 (-1225 4100);
PAINT SKYBLUE (-1225 4100);
FORCEPROP 1 LASTPIN (-1275 4150) $PN 1
J 0
(-1265 4130);
DISPLAY 0.617021 (-1265 4130);
PAINT WHITE (-1265 4130);
FORCEPROP 2 LAST CDS_LIB mstr_discrete
J 0
(-1275 4050);
DISPLAY 1.617021 (-1275 4050);
PAINT ORANGE (-1275 4050);
DISPLAY INVISIBLE (-1275 4050);
FORCEPROP 2 LAST ROOM PVCCIO_CPU0
J 0
(-1225 4200);
DISPLAY 2.212766 (-1225 4200);
PAINT WHITE (-1225 4200);
DISPLAY INVISIBLE (-1225 4200);
FORCEPROP 1 LAST PATH I33
J 0
(-1225 4200);
DISPLAY 0.978723 (-1225 4200);
PAINT WHITE (-1225 4200);
DISPLAY INVISIBLE (-1225 4200);
FORCEPROP 2 LAST CDS_LOCATION C7C18
J 0
(-1225 4150);
DISPLAY 0.617021 (-1225 4150);
PAINT AQUA (-1225 4150);
DISPLAY INVISIBLE (-1225 4150);
FORCEPROP 2 LAST SEC 1
J 0
(-1225 4250);
DISPLAY 1.106383 (-1225 4250);
PAINT MONO (-1225 4250);
DISPLAY INVISIBLE (-1225 4250);
FORCEPROP 2 LAST SEC_TYPE 0402
J 0
(-1225 4250);
DISPLAY 1.659574 (-1225 4250);
PAINT ORANGE (-1225 4250);
DISPLAY INVISIBLE (-1225 4250);
FORCEADD CAP_A..1
R 2
(-1425 4050);
FORCEPROP 1 LAST PART_NUMBER D97712-004
J 2
(-1475 3900);
DISPLAY 0.617021 (-1475 3900);
PAINT BLUE (-1475 3900);
FORCEPROP 1 LAST PACK_TYPE 0402V
J 2
(-1475 3850);
DISPLAY 0.617021 (-1475 3850);
PAINT SKYBLUE (-1475 3850);
FORCEPROP 1 LAST MATERIAL X6S
J 2
(-1475 3950);
DISPLAY 0.617021 (-1475 3950);
PAINT SKYBLUE (-1475 3950);
FORCEPROP 1 LAST VOLTAGE 6.3V
J 2
(-1475 4050);
DISPLAY 0.617021 (-1475 4050);
PAINT SKYBLUE (-1475 4050);
FORCEPROP 1 LAST TOLERANCE 10%
J 2
(-1475 4000);
DISPLAY 0.617021 (-1475 4000);
PAINT SKYBLUE (-1475 4000);
FORCEPROP 1 LASTPIN (-1425 3950) $PN 2
J 2
(-1435 3930);
DISPLAY 0.617021 (-1435 3930);
PAINT WHITE (-1435 3930);
FORCEPROP 1 LASTPIN (-1425 4150) $PN 1
J 2
(-1435 4130);
DISPLAY 0.617021 (-1435 4130);
PAINT WHITE (-1435 4130);
FORCEPROP 1 LAST VALUE 1.0UF
J 2
(-1475 4100);
DISPLAY 0.617021 (-1475 4100);
PAINT SKYBLUE (-1475 4100);
FORCEPROP 1 LAST LOCATION C7C20
J 2
(-1475 4150);
DISPLAY 0.617021 (-1475 4150);
PAINT AQUA (-1475 4150);
FORCEPROP 2 LAST CDS_LIB dev_discrete
J 0
(-1425 4050);
PAINT ORANGE (-1425 4050);
DISPLAY INVISIBLE (-1425 4050);
FORCEPROP 2 LAST CDS_SEC 1
J 0
(-1475 4200);
PAINT ORANGE (-1475 4200);
DISPLAY INVISIBLE (-1475 4200);
FORCEPROP 2 LAST SEC_TYPE 0402V
J 0
(-1475 4250);
DISPLAY 1.659574 (-1475 4250);
PAINT ORANGE (-1475 4250);
DISPLAY INVISIBLE (-1475 4250);
FORCEPROP 2 LAST SEC 1
J 0
(-1475 4250);
DISPLAY 1.106383 (-1475 4250);
PAINT MONO (-1475 4250);
DISPLAY INVISIBLE (-1475 4250);
FORCEPROP 1 LAST PATH I34
J 2
(-1475 4200);
DISPLAY 0.978723 (-1475 4200);
PAINT WHITE (-1475 4200);
DISPLAY INVISIBLE (-1475 4200);
FORCEPROP 2 LAST ROOM PVCCIO_CPU0
J 0
(-1475 4200);
DISPLAY 2.212766 (-1475 4200);
PAINT WHITE (-1475 4200);
DISPLAY INVISIBLE (-1475 4200);
FORCEADD CAP..1
(-1975 4000);
FORCEPROP 1 LAST PART_NUMBER D97712-011
J 0
(-1925 3850);
DISPLAY 0.617021 (-1925 3850);
PAINT BLUE (-1925 3850);
FORCEPROP 1 LAST PACK_TYPE 0402
J 0
(-1925 3800);
DISPLAY 0.617021 (-1925 3800);
PAINT SKYBLUE (-1925 3800);
FORCEPROP 1 LAST TOLERANCE 10%
J 0
(-1925 3950);
DISPLAY 0.617021 (-1925 3950);
PAINT SKYBLUE (-1925 3950);
FORCEPROP 1 LAST VOLTAGE 16V
J 0
(-1925 4000);
DISPLAY 0.617021 (-1925 4000);
PAINT SKYBLUE (-1925 4000);
FORCEPROP 1 LAST MATERIAL X6S
J 0
(-1925 3900);
DISPLAY 0.617021 (-1925 3900);
PAINT SKYBLUE (-1925 3900);
FORCEPROP 1 LASTPIN (-1975 3900) $PN 2
J 0
(-1965 3880);
DISPLAY 0.617021 (-1965 3880);
PAINT WHITE (-1965 3880);
FORCEPROP 1 LAST VALUE 1.0UF
J 0
(-1925 4050);
DISPLAY 0.617021 (-1925 4050);
PAINT SKYBLUE (-1925 4050);
FORCEPROP 1 LASTPIN (-1975 4100) $PN 1
J 0
(-1965 4080);
DISPLAY 0.617021 (-1965 4080);
PAINT WHITE (-1965 4080);
FORCEPROP 1 LAST LOCATION C7C17
J 0
(-1925 4100);
DISPLAY 0.617021 (-1925 4100);
PAINT AQUA (-1925 4100);
FORCEPROP 2 LAST CDS_LIB mstr_discrete
J 0
(-1975 4000);
DISPLAY 1.617021 (-1975 4000);
PAINT ORANGE (-1975 4000);
DISPLAY INVISIBLE (-1975 4000);
FORCEPROP 1 LAST PATH I36
J 0
(-1925 4150);
DISPLAY 0.978723 (-1925 4150);
PAINT WHITE (-1925 4150);
DISPLAY INVISIBLE (-1925 4150);
FORCEPROP 2 LAST CDS_LOCATION C7C17
J 0
(-1925 4100);
DISPLAY 0.617021 (-1925 4100);
PAINT AQUA (-1925 4100);
DISPLAY INVISIBLE (-1925 4100);
FORCEPROP 2 LAST ROOM PVCCIO_CPU0
J 0
(-1925 4150);
DISPLAY 2.212766 (-1925 4150);
PAINT WHITE (-1925 4150);
DISPLAY INVISIBLE (-1925 4150);
FORCEPROP 2 LAST SEC 1
J 0
(-1925 4200);
DISPLAY 1.106383 (-1925 4200);
PAINT MONO (-1925 4200);
DISPLAY INVISIBLE (-1925 4200);
FORCEPROP 2 LAST SEC_TYPE 0402
J 0
(-1925 4200);
DISPLAY 1.659574 (-1925 4200);
PAINT ORANGE (-1925 4200);
DISPLAY INVISIBLE (-1925 4200);
FORCEADD CAP..1
R 2
(-2025 3425);
FORCEPROP 1 LAST PART_NUMBER A36096-104
J 2
(-2075 3275);
DISPLAY 0.617021 (-2075 3275);
PAINT BLUE (-2075 3275);
FORCEPROP 1 LAST TOLERANCE 10%
J 2
(-2075 3375);
DISPLAY 0.617021 (-2075 3375);
PAINT SKYBLUE (-2075 3375);
FORCEPROP 1 LAST VOLTAGE 16V
J 2
(-2075 3425);
DISPLAY 0.617021 (-2075 3425);
PAINT SKYBLUE (-2075 3425);
FORCEPROP 1 LAST VALUE 0.220UF
J 2
(-2075 3475);
DISPLAY 0.617021 (-2075 3475);
PAINT SKYBLUE (-2075 3475);
FORCEPROP 1 LAST MATERIAL X7R
J 2
(-2075 3325);
DISPLAY 0.617021 (-2075 3325);
PAINT SKYBLUE (-2075 3325);
FORCEPROP 1 LASTPIN (-2025 3325) $PN 2
J 2
(-2035 3305);
DISPLAY 0.617021 (-2035 3305);
PAINT ORANGE (-2035 3305);
FORCEPROP 1 LAST PACK_TYPE 0402
J 2
(-2075 3225);
DISPLAY 0.617021 (-2075 3225);
PAINT SKYBLUE (-2075 3225);
FORCEPROP 1 LAST LOCATION C7C14
J 2
(-2075 3525);
DISPLAY 0.617021 (-2075 3525);
PAINT AQUA (-2075 3525);
FORCEPROP 1 LASTPIN (-2025 3525) $PN 1
J 2
(-2035 3505);
DISPLAY 0.617021 (-2035 3505);
PAINT ORANGE (-2035 3505);
FORCEPROP 2 LAST SEC 1
J 0
(-2075 3625);
DISPLAY 0.680851 (-2075 3625);
PAINT MONO (-2075 3625);
DISPLAY INVISIBLE (-2075 3625);
FORCEPROP 2 LAST SEC_TYPE 0402
J 0
(-2075 3625);
DISPLAY 1.021277 (-2075 3625);
PAINT ORANGE (-2075 3625);
DISPLAY INVISIBLE (-2075 3625);
FORCEPROP 0 LAST SPOF TRUE
J 0
(-2075 3625);
DISPLAY 1.021277 (-2075 3625);
PAINT ORANGE (-2075 3625);
DISPLAY INVISIBLE (-2075 3625);
FORCEPROP 2 LAST ROOM PVCCIO_CPU0
J 0
(-2075 3575);
DISPLAY 2.212766 (-2075 3575);
PAINT WHITE (-2075 3575);
DISPLAY INVISIBLE (-2075 3575);
FORCEPROP 1 LAST PATH I37
J 2
(-2075 3575);
DISPLAY 0.978723 (-2075 3575);
PAINT WHITE (-2075 3575);
DISPLAY INVISIBLE (-2075 3575);
FORCEPROP 2 LAST CDS_LOCATION C7C14
J 2
(-2075 3525);
DISPLAY 0.617021 (-2075 3525);
PAINT AQUA (-2075 3525);
DISPLAY INVISIBLE (-2075 3525);
FORCEPROP 2 LAST CDS_LIB mstr_discrete
J 0
(-2025 3425);
PAINT ORANGE (-2025 3425);
DISPLAY INVISIBLE (-2025 3425);
FORCEADD CAP_A..1
(-2200 4000);
FORCEPROP 1 LASTPIN (-2200 3900) $PN 2
J 0
(-2190 3880);
DISPLAY 0.617021 (-2190 3880);
PAINT WHITE (-2190 3880);
FORCEPROP 1 LASTPIN (-2200 4100) $PN 1
J 0
(-2190 4080);
DISPLAY 0.617021 (-2190 4080);
PAINT WHITE (-2190 4080);
FORCEPROP 1 LAST LOCATION C7C11
J 0
(-2150 4100);
DISPLAY 0.617021 (-2150 4100);
PAINT AQUA (-2150 4100);
FORCEPROP 1 LAST VALUE 0.1UF
J 0
(-2150 4050);
DISPLAY 0.617021 (-2150 4050);
PAINT SKYBLUE (-2150 4050);
FORCEPROP 1 LAST VOLTAGE 16V
J 0
(-2150 4000);
DISPLAY 0.617021 (-2150 4000);
PAINT SKYBLUE (-2150 4000);
FORCEPROP 1 LAST TOLERANCE 10%
J 0
(-2150 3950);
DISPLAY 0.617021 (-2150 3950);
PAINT SKYBLUE (-2150 3950);
FORCEPROP 1 LAST MATERIAL X7R
J 0
(-2150 3900);
DISPLAY 0.617021 (-2150 3900);
PAINT SKYBLUE (-2150 3900);
FORCEPROP 1 LAST PART_NUMBER A36096-030
J 0
(-2150 3850);
DISPLAY 0.617021 (-2150 3850);
PAINT BLUE (-2150 3850);
FORCEPROP 1 LAST PACK_TYPE 0402V
J 0
(-2150 3800);
DISPLAY 0.617021 (-2150 3800);
PAINT SKYBLUE (-2150 3800);
FORCEPROP 2 LAST CDS_LIB dev_discrete
J 0
(-2200 4000);
PAINT ORANGE (-2200 4000);
DISPLAY INVISIBLE (-2200 4000);
FORCEPROP 2 LAST ROOM PVCCIO_CPU0
J 0
(-2150 4150);
DISPLAY 2.212766 (-2150 4150);
PAINT WHITE (-2150 4150);
DISPLAY INVISIBLE (-2150 4150);
FORCEPROP 2 LAST SEC 1
J 0
(-2150 4200);
DISPLAY 1.106383 (-2150 4200);
PAINT MONO (-2150 4200);
DISPLAY INVISIBLE (-2150 4200);
FORCEPROP 2 LAST SEC_TYPE 0402V
J 0
(-2150 4200);
DISPLAY 1.659574 (-2150 4200);
PAINT ORANGE (-2150 4200);
DISPLAY INVISIBLE (-2150 4200);
FORCEPROP 2 LAST CDS_SEC 1
J 0
(-2150 4150);
PAINT ORANGE (-2150 4150);
DISPLAY INVISIBLE (-2150 4150);
FORCEPROP 2 LAST CDS_LOCATION C7C11
J 0
(-2150 4100);
DISPLAY 0.617021 (-2150 4100);
PAINT AQUA (-2150 4100);
DISPLAY INVISIBLE (-2150 4100);
FORCEPROP 1 LAST PATH I38
J 0
(-2150 4150);
DISPLAY 0.978723 (-2150 4150);
PAINT WHITE (-2150 4150);
DISPLAY INVISIBLE (-2150 4150);
FORCEADD CAP..1
(-2450 4025);
FORCEPROP 1 LASTPIN (-2450 3925) $PN 2
J 0
(-2440 3905);
DISPLAY 0.617021 (-2440 3905);
PAINT WHITE (-2440 3905);
FORCEPROP 1 LAST MATERIAL X6S
J 0
(-2400 3925);
DISPLAY 0.617021 (-2400 3925);
PAINT SKYBLUE (-2400 3925);
FORCEPROP 1 LAST VOLTAGE 16V
J 0
(-2400 4025);
DISPLAY 0.617021 (-2400 4025);
PAINT SKYBLUE (-2400 4025);
FORCEPROP 1 LAST TOLERANCE 10%
J 0
(-2400 3975);
DISPLAY 0.617021 (-2400 3975);
PAINT SKYBLUE (-2400 3975);
FORCEPROP 1 LAST PACK_TYPE 0402
J 0
(-2400 3825);
DISPLAY 0.617021 (-2400 3825);
PAINT SKYBLUE (-2400 3825);
FORCEPROP 1 LAST PART_NUMBER D97712-011
J 0
(-2400 3875);
DISPLAY 0.617021 (-2400 3875);
PAINT BLUE (-2400 3875);
FORCEPROP 1 LAST VALUE 1.0UF
J 0
(-2400 4075);
DISPLAY 0.617021 (-2400 4075);
PAINT SKYBLUE (-2400 4075);
FORCEPROP 1 LASTPIN (-2450 4125) $PN 1
J 0
(-2440 4105);
DISPLAY 0.617021 (-2440 4105);
PAINT WHITE (-2440 4105);
FORCEPROP 1 LAST LOCATION C7C12
J 0
(-2400 4125);
DISPLAY 0.617021 (-2400 4125);
PAINT AQUA (-2400 4125);
FORCEPROP 2 LAST CDS_LIB mstr_discrete
J 0
(-2450 4025);
DISPLAY 1.617021 (-2450 4025);
PAINT ORANGE (-2450 4025);
DISPLAY INVISIBLE (-2450 4025);
FORCEPROP 2 LAST SEC_TYPE 0402
J 0
(-2400 4225);
DISPLAY 1.659574 (-2400 4225);
PAINT ORANGE (-2400 4225);
DISPLAY INVISIBLE (-2400 4225);
FORCEPROP 2 LAST SEC 1
J 0
(-2400 4225);
DISPLAY 1.106383 (-2400 4225);
PAINT MONO (-2400 4225);
DISPLAY INVISIBLE (-2400 4225);
FORCEPROP 2 LAST CDS_LOCATION C7C12
J 0
(-2400 4125);
DISPLAY 0.617021 (-2400 4125);
PAINT AQUA (-2400 4125);
DISPLAY INVISIBLE (-2400 4125);
FORCEPROP 1 LAST PATH I39
J 0
(-2400 4175);
DISPLAY 0.978723 (-2400 4175);
PAINT WHITE (-2400 4175);
DISPLAY INVISIBLE (-2400 4175);
FORCEPROP 2 LAST ROOM PVCCIO_CPU0
J 0
(-2400 4175);
DISPLAY 2.212766 (-2400 4175);
PAINT WHITE (-2400 4175);
DISPLAY INVISIBLE (-2400 4175);
FORCEADD CAP..1
(-2675 4000);
FORCEPROP 1 LASTPIN (-2675 3900) $PN 2
J 0
(-2665 3880);
DISPLAY 0.617021 (-2665 3880);
PAINT WHITE (-2665 3880);
FORCEPROP 1 LAST MATERIAL X6S
J 0
(-2625 3900);
DISPLAY 0.617021 (-2625 3900);
PAINT SKYBLUE (-2625 3900);
FORCEPROP 1 LAST VOLTAGE 16V
J 0
(-2625 4000);
DISPLAY 0.617021 (-2625 4000);
PAINT SKYBLUE (-2625 4000);
FORCEPROP 1 LAST PACK_TYPE 0805
J 0
(-2625 3800);
DISPLAY 0.617021 (-2625 3800);
PAINT SKYBLUE (-2625 3800);
FORCEPROP 1 LAST TOLERANCE 10%
J 0
(-2625 3950);
DISPLAY 0.617021 (-2625 3950);
PAINT SKYBLUE (-2625 3950);
FORCEPROP 1 LAST VALUE 10UF
J 0
(-2625 4050);
DISPLAY 0.617021 (-2625 4050);
PAINT SKYBLUE (-2625 4050);
FORCEPROP 1 LAST PART_NUMBER C95333-007
J 0
(-2625 3850);
DISPLAY 0.617021 (-2625 3850);
PAINT BLUE (-2625 3850);
FORCEPROP 1 LASTPIN (-2675 4100) $PN 1
J 0
(-2665 4080);
DISPLAY 0.617021 (-2665 4080);
PAINT WHITE (-2665 4080);
FORCEPROP 1 LAST LOCATION C3N36
J 0
(-2625 4100);
DISPLAY 0.617021 (-2625 4100);
PAINT AQUA (-2625 4100);
FORCEPROP 2 LAST CDS_LIB mstr_discrete
J 0
(-2675 4000);
DISPLAY 1.617021 (-2675 4000);
PAINT ORANGE (-2675 4000);
DISPLAY INVISIBLE (-2675 4000);
FORCEPROP 2 LAST SEC_TYPE 0805
J 0
(-2625 4200);
DISPLAY 1.659574 (-2625 4200);
PAINT ORANGE (-2625 4200);
DISPLAY INVISIBLE (-2625 4200);
FORCEPROP 2 LAST SEC 1
J 0
(-2625 4200);
DISPLAY 1.106383 (-2625 4200);
PAINT MONO (-2625 4200);
DISPLAY INVISIBLE (-2625 4200);
FORCEPROP 2 LAST CDS_LOCATION C3N36
J 0
(-2625 4100);
DISPLAY 0.617021 (-2625 4100);
PAINT AQUA (-2625 4100);
DISPLAY INVISIBLE (-2625 4100);
FORCEPROP 1 LAST PATH I40
J 0
(-2625 4150);
DISPLAY 0.978723 (-2625 4150);
PAINT WHITE (-2625 4150);
DISPLAY INVISIBLE (-2625 4150);
FORCEPROP 2 LAST ROOM PVCCIO_CPU0
J 0
(-2625 4150);
DISPLAY 2.212766 (-2625 4150);
PAINT WHITE (-2625 4150);
DISPLAY INVISIBLE (-2625 4150);
FORCEADD CAP..1
(-2900 4050);
FORCEPROP 1 LASTPIN (-2900 3950) $PN 2
J 0
(-2890 3930);
DISPLAY 0.617021 (-2890 3930);
PAINT WHITE (-2890 3930);
FORCEPROP 1 LAST MATERIAL X6S
J 0
(-2850 3950);
DISPLAY 0.617021 (-2850 3950);
PAINT SKYBLUE (-2850 3950);
FORCEPROP 1 LAST VOLTAGE 16V
J 0
(-2850 4050);
DISPLAY 0.617021 (-2850 4050);
PAINT SKYBLUE (-2850 4050);
FORCEPROP 1 LAST PACK_TYPE 0805
J 0
(-2850 3850);
DISPLAY 0.617021 (-2850 3850);
PAINT SKYBLUE (-2850 3850);
FORCEPROP 1 LAST TOLERANCE 10%
J 0
(-2850 4000);
DISPLAY 0.617021 (-2850 4000);
PAINT SKYBLUE (-2850 4000);
FORCEPROP 1 LAST PART_NUMBER C95333-007
J 0
(-2850 3900);
DISPLAY 0.617021 (-2850 3900);
PAINT BLUE (-2850 3900);
FORCEPROP 1 LASTPIN (-2900 4150) $PN 1
J 0
(-2890 4130);
DISPLAY 0.617021 (-2890 4130);
PAINT WHITE (-2890 4130);
FORCEPROP 1 LAST VALUE 10UF
J 0
(-2850 4100);
DISPLAY 0.617021 (-2850 4100);
PAINT SKYBLUE (-2850 4100);
FORCEPROP 1 LAST LOCATION C3N33
J 0
(-2850 4150);
DISPLAY 0.617021 (-2850 4150);
PAINT AQUA (-2850 4150);
FORCEPROP 2 LAST CDS_LIB mstr_discrete
J 0
(-2900 4050);
DISPLAY 1.617021 (-2900 4050);
PAINT ORANGE (-2900 4050);
DISPLAY INVISIBLE (-2900 4050);
FORCEPROP 2 LAST CDS_LOCATION C3N33
J 0
(-2850 4150);
DISPLAY 0.617021 (-2850 4150);
PAINT AQUA (-2850 4150);
DISPLAY INVISIBLE (-2850 4150);
FORCEPROP 2 LAST SEC_TYPE 0805
J 0
(-2850 4250);
DISPLAY 1.659574 (-2850 4250);
PAINT ORANGE (-2850 4250);
DISPLAY INVISIBLE (-2850 4250);
FORCEPROP 1 LAST PATH I41
J 0
(-2850 4200);
DISPLAY 0.978723 (-2850 4200);
PAINT WHITE (-2850 4200);
DISPLAY INVISIBLE (-2850 4200);
FORCEPROP 2 LAST SEC 1
J 0
(-2850 4250);
DISPLAY 1.106383 (-2850 4250);
PAINT MONO (-2850 4250);
DISPLAY INVISIBLE (-2850 4250);
FORCEPROP 2 LAST ROOM PVCCIO_CPU0
J 0
(-2850 4200);
DISPLAY 2.212766 (-2850 4200);
PAINT WHITE (-2850 4200);
DISPLAY INVISIBLE (-2850 4200);
FORCEADD CAP..1
(-3150 4050);
FORCEPROP 1 LASTPIN (-3150 3950) $PN 2
J 0
(-3140 3930);
DISPLAY 0.617021 (-3140 3930);
PAINT WHITE (-3140 3930);
FORCEPROP 1 LAST MATERIAL X6S
J 0
(-3100 3950);
DISPLAY 0.617021 (-3100 3950);
PAINT SKYBLUE (-3100 3950);
FORCEPROP 1 LAST VOLTAGE 16V
J 0
(-3100 4050);
DISPLAY 0.617021 (-3100 4050);
PAINT SKYBLUE (-3100 4050);
FORCEPROP 1 LAST PACK_TYPE 0805
J 0
(-3100 3850);
DISPLAY 0.617021 (-3100 3850);
PAINT SKYBLUE (-3100 3850);
FORCEPROP 1 LAST TOLERANCE 10%
J 0
(-3100 4000);
DISPLAY 0.617021 (-3100 4000);
PAINT SKYBLUE (-3100 4000);
FORCEPROP 1 LAST PART_NUMBER C95333-007
J 0
(-3100 3900);
DISPLAY 0.617021 (-3100 3900);
PAINT BLUE (-3100 3900);
FORCEPROP 1 LASTPIN (-3150 4150) $PN 1
J 0
(-3140 4130);
DISPLAY 0.617021 (-3140 4130);
PAINT WHITE (-3140 4130);
FORCEPROP 1 LAST VALUE 10UF
J 0
(-3100 4100);
DISPLAY 0.617021 (-3100 4100);
PAINT SKYBLUE (-3100 4100);
FORCEPROP 1 LAST LOCATION C3N34
J 0
(-3100 4150);
DISPLAY 0.617021 (-3100 4150);
PAINT AQUA (-3100 4150);
FORCEPROP 2 LAST CDS_LIB mstr_discrete
J 0
(-3150 4050);
DISPLAY 1.617021 (-3150 4050);
PAINT ORANGE (-3150 4050);
DISPLAY INVISIBLE (-3150 4050);
FORCEPROP 2 LAST CDS_LOCATION C3N34
J 0
(-3100 4150);
DISPLAY 0.617021 (-3100 4150);
PAINT AQUA (-3100 4150);
DISPLAY INVISIBLE (-3100 4150);
FORCEPROP 1 LAST PATH I43
J 0
(-3100 4200);
DISPLAY 0.978723 (-3100 4200);
PAINT WHITE (-3100 4200);
DISPLAY INVISIBLE (-3100 4200);
FORCEPROP 2 LAST ROOM PVCCIO_CPU0
J 0
(-3100 4200);
DISPLAY 2.212766 (-3100 4200);
PAINT WHITE (-3100 4200);
DISPLAY INVISIBLE (-3100 4200);
FORCEPROP 2 LAST SEC 1
J 0
(-3100 4250);
DISPLAY 1.106383 (-3100 4250);
PAINT MONO (-3100 4250);
DISPLAY INVISIBLE (-3100 4250);
FORCEPROP 2 LAST SEC_TYPE 0805
J 0
(-3100 4250);
DISPLAY 1.659574 (-3100 4250);
PAINT ORANGE (-3100 4250);
DISPLAY INVISIBLE (-3100 4250);
FORCEADD GND..1
(-3150 3675);
FORCEPROP 3 LASTPIN (-3150 3725) SIG_NAME GND\g
J 0
(-3140 3735);
DISPLAY 0.659574 (-3140 3735);
PAINT MONO (-3140 3735);
DISPLAY INVISIBLE (-3140 3735);
FORCEPROP 2 LAST ROOM PVCCIO_CPU0
J 0
(-3700 3750);
DISPLAY 3.127660 (-3700 3750);
PAINT WHITE (-3700 3750);
DISPLAY INVISIBLE (-3700 3750);
FORCEPROP 2 LAST BOM_COST PROC_VRD_PVCCIO_CPU0
J 0
(-3525 3750);
DISPLAY 2.340426 (-3525 3750);
PAINT WHITE (-3525 3750);
DISPLAY INVISIBLE (-3525 3750);
FORCEPROP 1 LAST PATH I44
J 0
(-3075 3675);
DISPLAY 0.872340 (-3075 3675);
PAINT AQUA (-3075 3675);
DISPLAY INVISIBLE (-3075 3675);
FORCEPROP 1 LAST VOLTAGE 0.0V
J 0
(-3195 3632);
DISPLAY 0.340426 (-3195 3632);
PAINT SKYBLUE (-3195 3632);
DISPLAY INVISIBLE (-3195 3632);
FORCEPROP 2 LAST CDS_LIB mstr_symbols
J 0
(-3150 3675);
DISPLAY 1.617021 (-3150 3675);
PAINT ORANGE (-3150 3675);
DISPLAY INVISIBLE (-3150 3675);
FORCEPROP 1 LAST SIZE 1B
J 0
(-3075 3625);
DISPLAY 2.787234 (-3075 3625);
PAINT GREEN (-3075 3625);
DISPLAY INVISIBLE (-3075 3625);
FORCEPROP 1 LAST BODY_TYPE PLUMBING
J 0
(-3195 3632);
DISPLAY 0.340426 (-3195 3632);
PAINT GREEN (-3195 3632);
DISPLAY INVISIBLE (-3195 3632);
FORCEPROP 1 LAST HDL_POWER GND
J 0
(-3150 3825);
DISPLAY 2.787234 (-3150 3825);
PAINT GREEN (-3150 3825);
DISPLAY INVISIBLE (-3150 3825);
FORCEADD OFFPAGE..1
(-2425 3675);
FORCEPROP 2 LAST $XR0 211 
J 0
(-2677 3675);
DISPLAY 0.638298 (-2677 3675);
PAINT MONO (-2677 3675);
FORCEPROP 2 LAST ROOM PVCCIO_CPU0
J 0
(-2825 3750);
DISPLAY 3.127660 (-2825 3750);
PAINT WHITE (-2825 3750);
DISPLAY INVISIBLE (-2825 3750);
FORCEPROP 2 LAST BOM_COST PROC_VRD_PVCCIO_CPU0
J 0
(-2675 3725);
DISPLAY 2.340426 (-2675 3725);
PAINT WHITE (-2675 3725);
DISPLAY INVISIBLE (-2675 3725);
FORCEPROP 2 LAST PATH I45
J 0
(-2675 3725);
DISPLAY 1.021277 (-2675 3725);
PAINT ORANGE (-2675 3725);
DISPLAY INVISIBLE (-2675 3725);
FORCEPROP 2 LAST CDS_LIB mstr_standard
J 0
(-2425 3675);
DISPLAY 1.617021 (-2425 3675);
PAINT ORANGE (-2425 3675);
DISPLAY INVISIBLE (-2425 3675);
FORCEPROP 1 LAST OFFPAGE TRUE
J 0
(-2100 3550);
PAINT GREEN (-2100 3550);
DISPLAY INVISIBLE (-2100 3550);
FORCEPROP 1 LAST COMMENT_BODY TRUE
J 0
(-2300 3575);
DISPLAY 2.723404 (-2300 3575);
PAINT PEACH (-2300 3575);
DISPLAY INVISIBLE (-2300 3575);
FORCEADD CAP..1
R 2
(1400 2225);
FORCEPROP 1 LAST PART_NUMBER 644066-127
J 2
(1379 2029);
DISPLAY 0.617021 (1379 2029);
PAINT BLUE (1379 2029);
FORCEPROP 1 LAST LOCATION C7C8
J 2
(1350 2325);
DISPLAY 0.617021 (1350 2325);
PAINT AQUA (1350 2325);
FORCEPROP 1 LAST MATERIAL X5R
J 2
(1350 2125);
DISPLAY 0.617021 (1350 2125);
PAINT SKYBLUE (1350 2125);
FORCEPROP 1 LAST VOLTAGE 16V
J 2
(1350 2225);
DISPLAY 0.617021 (1350 2225);
PAINT SKYBLUE (1350 2225);
FORCEPROP 1 LAST PACK_TYPE 1210
J 2
(1375 2075);
DISPLAY 0.617021 (1375 2075);
PAINT SKYBLUE (1375 2075);
FORCEPROP 1 LAST TOLERANCE 20%
J 2
(1350 2175);
DISPLAY 0.617021 (1350 2175);
PAINT SKYBLUE (1350 2175);
FORCEPROP 1 LAST VALUE 100UF
J 2
(1350 2275);
DISPLAY 0.617021 (1350 2275);
PAINT SKYBLUE (1350 2275);
FORCEPROP 1 LASTPIN (1400 2125) $PN 2
J 2
(1390 2105);
DISPLAY 0.617021 (1390 2105);
PAINT ORANGE (1390 2105);
FORCEPROP 1 LASTPIN (1400 2325) $PN 1
J 2
(1390 2305);
DISPLAY 0.617021 (1390 2305);
PAINT ORANGE (1390 2305);
FORCEPROP 2 LAST CDS_LIB mstr_discrete
J 0
(1400 2225);
PAINT ORANGE (1400 2225);
DISPLAY INVISIBLE (1400 2225);
FORCEPROP 2 LAST CDS_LOCATION C7C8
J 2
(1350 2325);
DISPLAY 0.617021 (1350 2325);
PAINT AQUA (1350 2325);
DISPLAY INVISIBLE (1350 2325);
FORCEPROP 1 LAST PATH I51
J 2
(1350 2375);
DISPLAY 0.978723 (1350 2375);
PAINT WHITE (1350 2375);
DISPLAY INVISIBLE (1350 2375);
FORCEPROP 2 LAST SEC 1
J 0
(1350 2425);
DISPLAY 0.680851 (1350 2425);
PAINT MONO (1350 2425);
DISPLAY INVISIBLE (1350 2425);
FORCEPROP 2 LAST SEC_TYPE 1210
J 0
(1350 2425);
DISPLAY 1.021277 (1350 2425);
PAINT ORANGE (1350 2425);
DISPLAY INVISIBLE (1350 2425);
FORCEPROP 2 LAST BOM_COST PROC_VRD_VCCIO_CPU1
J 0
(1350 2375);
DISPLAY 0.723404 (1350 2375);
PAINT ORANGE (1350 2375);
DISPLAY INVISIBLE (1350 2375);
FORCEPROP 2 LAST ROOM PVCCIO_CPU1
J 0
(1350 2375);
DISPLAY 0.723404 (1350 2375);
PAINT ORANGE (1350 2375);
DISPLAY INVISIBLE (1350 2375);
FORCEADD GND..1
(1400 1975);
FORCEPROP 3 LASTPIN (1400 2025) SIG_NAME GND\g
J 0
(1410 2035);
DISPLAY 0.659574 (1410 2035);
PAINT MONO (1410 2035);
DISPLAY INVISIBLE (1410 2035);
FORCEPROP 2 LAST BOM_COST MEM_VRD_PVCCIO_CPU1
J 0
(1050 2050);
DISPLAY 0.617021 (1050 2050);
PAINT ORANGE (1050 2050);
DISPLAY INVISIBLE (1050 2050);
FORCEPROP 2 LAST ROOM PVCCIO_CPU1
J 0
(1100 2050);
DISPLAY 0.723404 (1100 2050);
PAINT ORANGE (1100 2050);
DISPLAY INVISIBLE (1100 2050);
FORCEPROP 1 LAST SIZE 1B
J 0
(1475 1925);
DISPLAY 0.553191 (1475 1925);
PAINT ORANGE (1475 1925);
DISPLAY INVISIBLE (1475 1925);
FORCEPROP 2 LAST CDS_LIB mstr_symbols
J 0
(1400 1975);
PAINT ORANGE (1400 1975);
DISPLAY INVISIBLE (1400 1975);
FORCEPROP 1 LAST PATH I52
J 0
(1475 1975);
DISPLAY 0.872340 (1475 1975);
PAINT AQUA (1475 1975);
DISPLAY INVISIBLE (1475 1975);
FORCEPROP 1 LAST VOLTAGE 0.0V
J 0
(1355 1932);
DISPLAY 0.340426 (1355 1932);
PAINT SKYBLUE (1355 1932);
DISPLAY INVISIBLE (1355 1932);
FORCEPROP 1 LAST BODY_TYPE PLUMBING
J 0
(1355 1932);
DISPLAY 0.340426 (1355 1932);
PAINT GREEN (1355 1932);
DISPLAY INVISIBLE (1355 1932);
FORCEPROP 1 LAST HDL_POWER GND
J 0
(1400 2125);
DISPLAY 0.553191 (1400 2125);
PAINT GREEN (1400 2125);
DISPLAY INVISIBLE (1400 2125);
FORCEADD CAP..1
(825 2200);
FORCEPROP 1 LAST LOCATION C7C7
J 0
(875 2300);
DISPLAY 0.617021 (875 2300);
PAINT AQUA (875 2300);
FORCEPROP 1 LASTPIN (825 2300) $PN 1
J 0
(835 2280);
DISPLAY 0.617021 (835 2280);
PAINT ORANGE (835 2280);
FORCEPROP 1 LAST VOLTAGE 16V
J 0
(875 2200);
DISPLAY 0.617021 (875 2200);
PAINT SKYBLUE (875 2200);
FORCEPROP 1 LAST PACK_TYPE 1210
J 0
(875 2000);
DISPLAY 0.617021 (875 2000);
PAINT SKYBLUE (875 2000);
FORCEPROP 1 LASTPIN (825 2100) $PN 2
J 0
(835 2080);
DISPLAY 0.617021 (835 2080);
PAINT ORANGE (835 2080);
FORCEPROP 1 LAST MATERIAL X5R
J 0
(875 2100);
DISPLAY 0.617021 (875 2100);
PAINT SKYBLUE (875 2100);
FORCEPROP 1 LAST TOLERANCE 20%
J 0
(875 2150);
DISPLAY 0.617021 (875 2150);
PAINT SKYBLUE (875 2150);
FORCEPROP 1 LAST VALUE 100UF
J 0
(875 2250);
DISPLAY 0.617021 (875 2250);
PAINT SKYBLUE (875 2250);
FORCEPROP 1 LAST PART_NUMBER 644066-127
J 0
(875 2050);
DISPLAY 0.617021 (875 2050);
PAINT BLUE (875 2050);
FORCEPROP 2 LAST CDS_LIB mstr_discrete
J 0
(825 2200);
PAINT ORANGE (825 2200);
DISPLAY INVISIBLE (825 2200);
FORCEPROP 2 LAST CDS_LOCATION C7C7
J 0
(875 2300);
DISPLAY 0.617021 (875 2300);
PAINT AQUA (875 2300);
DISPLAY INVISIBLE (875 2300);
FORCEPROP 2 LAST BOM_COST PROC_VRD_VCCIO_CPU1
J 0
(875 2350);
DISPLAY 0.829787 (875 2350);
PAINT PURPLE (875 2350);
DISPLAY INVISIBLE (875 2350);
FORCEPROP 1 LAST PATH I54
J 0
(875 2350);
DISPLAY 0.978723 (875 2350);
PAINT WHITE (875 2350);
DISPLAY INVISIBLE (875 2350);
FORCEPROP 2 LAST ROOM PVCCIO_CPU1
J 0
(875 2350);
DISPLAY 0.829787 (875 2350);
PAINT ORANGE (875 2350);
DISPLAY INVISIBLE (875 2350);
FORCEPROP 2 LAST SEC_TYPE 1210
J 0
(875 2400);
DISPLAY 1.021277 (875 2400);
PAINT ORANGE (875 2400);
DISPLAY INVISIBLE (875 2400);
FORCEPROP 2 LAST SEC 1
J 0
(875 2400);
DISPLAY 0.680851 (875 2400);
PAINT MONO (875 2400);
DISPLAY INVISIBLE (875 2400);
FORCEADD GND..1
(825 1975);
FORCEPROP 3 LASTPIN (825 2025) SIG_NAME GND\g
J 0
(835 2035);
DISPLAY 0.659574 (835 2035);
PAINT MONO (835 2035);
DISPLAY INVISIBLE (835 2035);
FORCEPROP 2 LAST BOM_COST MEM_VRD_PVCCIO_CPU1
J 0
(475 2050);
DISPLAY 0.617021 (475 2050);
PAINT ORANGE (475 2050);
DISPLAY INVISIBLE (475 2050);
FORCEPROP 2 LAST ROOM PVCCIO_CPU1
J 0
(525 2050);
DISPLAY 0.723404 (525 2050);
PAINT ORANGE (525 2050);
DISPLAY INVISIBLE (525 2050);
FORCEPROP 1 LAST VOLTAGE 0.0V
J 0
(780 1932);
DISPLAY 0.340426 (780 1932);
PAINT SKYBLUE (780 1932);
DISPLAY INVISIBLE (780 1932);
FORCEPROP 2 LAST CDS_LIB mstr_symbols
J 0
(825 1975);
PAINT ORANGE (825 1975);
DISPLAY INVISIBLE (825 1975);
FORCEPROP 1 LAST PATH I55
J 0
(900 1975);
DISPLAY 0.872340 (900 1975);
PAINT AQUA (900 1975);
DISPLAY INVISIBLE (900 1975);
FORCEPROP 1 LAST SIZE 1B
J 0
(900 1925);
DISPLAY 0.553191 (900 1925);
PAINT ORANGE (900 1925);
DISPLAY INVISIBLE (900 1925);
FORCEPROP 1 LAST BODY_TYPE PLUMBING
J 0
(780 1932);
DISPLAY 0.340426 (780 1932);
PAINT GREEN (780 1932);
DISPLAY INVISIBLE (780 1932);
FORCEPROP 1 LAST HDL_POWER GND
J 0
(825 2125);
DISPLAY 0.553191 (825 2125);
PAINT GREEN (825 2125);
DISPLAY INVISIBLE (825 2125);
FORCEADD INDUCTOR..1
(325 2450);
FORCEPROP 1 LAST PART_NUMBER D92183-020
J 0
(225 2550);
DISPLAY 0.617021 (225 2550);
PAINT BLUE (225 2550);
FORCEPROP 1 LAST LOCATION L7C1
J 0
(225 2500);
DISPLAY 0.617021 (225 2500);
PAINT AQUA (225 2500);
FORCEPROP 1 LAST VALUE 100NH
J 2
(320 2365);
DISPLAY 0.617021 (320 2365);
PAINT SKYBLUE (320 2365);
FORCEPROP 1 LAST MATERIAL IND
J 0
(340 2365);
DISPLAY 0.617021 (340 2365);
PAINT SKYBLUE (340 2365);
FORCEPROP 1 LASTPIN (425 2450) $PN 2
J 2
(435 2460);
DISPLAY 0.617021 (435 2460);
PAINT WHITE (435 2460);
FORCEPROP 1 LAST PACK_TYPE SM
J 0
(490 2365);
DISPLAY 0.617021 (490 2365);
PAINT SKYBLUE (490 2365);
FORCEPROP 1 LASTPIN (225 2450) $PN 1
J 0
(225 2460);
DISPLAY 0.617021 (225 2460);
PAINT WHITE (225 2460);
FORCEPROP 2 LAST SEC_TYPE SM
J 0
(225 2650);
DISPLAY 1.021277 (225 2650);
PAINT ORANGE (225 2650);
DISPLAY INVISIBLE (225 2650);
FORCEPROP 0 LAST BOM_COST PROC_VRD_VCCIO_CPU1
J 0
(225 2650);
DISPLAY 1.021277 (225 2650);
PAINT ORANGE (225 2650);
DISPLAY INVISIBLE (225 2650);
FORCEPROP 2 LAST SEC 1
J 0
(225 2650);
DISPLAY 0.680851 (225 2650);
PAINT MONO (225 2650);
DISPLAY INVISIBLE (225 2650);
FORCEPROP 2 LAST CDS_LOCATION L7C1
J 0
(225 2500);
DISPLAY 0.617021 (225 2500);
PAINT AQUA (225 2500);
DISPLAY INVISIBLE (225 2500);
FORCEPROP 1 LAST PATH I56
J 0
(225 2600);
DISPLAY 0.978723 (225 2600);
PAINT ORANGE (225 2600);
DISPLAY INVISIBLE (225 2600);
FORCEPROP 0 LAST ROOM PVCCIO_CPU1
J 0
(225 2650);
DISPLAY 1.021277 (225 2650);
PAINT ORANGE (225 2650);
DISPLAY INVISIBLE (225 2650);
FORCEPROP 2 LAST CDS_LIB mstr_discrete
J 0
(325 2450);
PAINT ORANGE (325 2450);
DISPLAY INVISIBLE (325 2450);
FORCEADD P12V_STBY..1
(-50 2550);
FORCEPROP 3 LASTPIN (-50 2500) SIG_NAME P12V_STBY\g
J 0
(-40 2510);
DISPLAY 0.659574 (-40 2510);
PAINT MONO (-40 2510);
DISPLAY INVISIBLE (-40 2510);
FORCEPROP 1 LAST SIZE 1B
J 0
(-5 2572);
DISPLAY 0.340426 (-5 2572);
PAINT GREEN (-5 2572);
DISPLAY INVISIBLE (-5 2572);
FORCEPROP 2 LAST CDS_LIB mstr_symbols
J 0
(-50 2550);
PAINT ORANGE (-50 2550);
DISPLAY INVISIBLE (-50 2550);
FORCEPROP 1 LAST PATH I57
J 0
(-5 2552);
DISPLAY 0.340426 (-5 2552);
PAINT GREEN (-5 2552);
DISPLAY INVISIBLE (-5 2552);
FORCEPROP 1 LAST VOLTAGE 12.0V
J 0
(-95 2507);
DISPLAY 0.340426 (-95 2507);
PAINT SKYBLUE (-95 2507);
DISPLAY INVISIBLE (-95 2507);
FORCEPROP 1 LAST BODY_TYPE PLUMBING
J 0
(-95 2507);
DISPLAY 0.340426 (-95 2507);
PAINT GREEN (-95 2507);
DISPLAY INVISIBLE (-95 2507);
FORCEPROP 1 LAST HDL_POWER P12V_STBY
J 0
(-350 2425);
DISPLAY 0.872340 (-350 2425);
PAINT ORANGE (-350 2425);
DISPLAY INVISIBLE (-350 2425);
FORCEADD P5V_STBY..1
(-425 4700);
FORCEPROP 3 LASTPIN (-425 4650) SIG_NAME P5V_STBY\g
J 0
(-415 4660);
DISPLAY 0.659574 (-415 4660);
PAINT MONO (-415 4660);
DISPLAY INVISIBLE (-415 4660);
FORCEPROP 1 LAST VOLTAGE 5.0V
J 0
(-470 4657);
DISPLAY 0.340426 (-470 4657);
PAINT SKYBLUE (-470 4657);
DISPLAY INVISIBLE (-470 4657);
FORCEPROP 1 LAST PATH I58
J 0
(-380 4702);
DISPLAY 0.340426 (-380 4702);
PAINT GREEN (-380 4702);
DISPLAY INVISIBLE (-380 4702);
FORCEPROP 2 LAST CDS_LIB mstr_symbols
J 0
(-425 4700);
PAINT ORANGE (-425 4700);
DISPLAY INVISIBLE (-425 4700);
FORCEPROP 1 LAST SIZE 1B
J 0
(-380 4722);
DISPLAY 0.340426 (-380 4722);
PAINT GREEN (-380 4722);
DISPLAY INVISIBLE (-380 4722);
FORCEPROP 1 LAST BODY_TYPE PLUMBING
J 0
(-470 4657);
DISPLAY 0.340426 (-470 4657);
PAINT GREEN (-470 4657);
DISPLAY INVISIBLE (-470 4657);
FORCEPROP 1 LAST HDL_POWER P5V_STBY
J 0
(-725 4575);
DISPLAY 0.872340 (-725 4575);
PAINT ORANGE (-725 4575);
DISPLAY INVISIBLE (-725 4575);
FORCEADD OFFPAGE..1
(-3225 1400);
FORCEPROP 2 LAST $XR0 39 
J 0
(-3476 1400);
DISPLAY 0.638298 (-3476 1400);
PAINT MONO (-3476 1400);
FORCEPROP 2 LAST ROOM VCCIN_CPU0_DECAP_VR
J 0
(-3750 1475);
PAINT ORANGE (-3750 1475);
DISPLAY INVISIBLE (-3750 1475);
FORCEPROP 2 LAST PATH I59
J 0
(-3425 1450);
DISPLAY 1.021277 (-3425 1450);
PAINT ORANGE (-3425 1450);
DISPLAY INVISIBLE (-3425 1450);
FORCEPROP 2 LAST BOM_COST PROC_VRD_VCCIN_CPU0
J 0
(-3425 1450);
PAINT MONO (-3425 1450);
DISPLAY INVISIBLE (-3425 1450);
FORCEPROP 2 LAST CDS_LIB mstr_standard
J 0
(-3225 1400);
PAINT ORANGE (-3225 1400);
DISPLAY INVISIBLE (-3225 1400);
FORCEPROP 1 LAST OFFPAGE TRUE
J 0
(-2900 1275);
DISPLAY 0.893617 (-2900 1275);
PAINT GREEN (-2900 1275);
DISPLAY INVISIBLE (-2900 1275);
FORCEPROP 1 LAST COMMENT_BODY TRUE
J 0
(-3100 1300);
DISPLAY 0.893617 (-3100 1300);
PAINT GREEN (-3100 1300);
DISPLAY INVISIBLE (-3100 1300);
FORCEADD CAP_A..1
(-1925 1675);
FORCEPROP 1 LAST TOLERANCE 10%
J 0
(-1875 1625);
DISPLAY 0.617021 (-1875 1625);
PAINT SKYBLUE (-1875 1625);
FORCEPROP 1 LAST VALUE 0.1UF
J 0
(-1875 1725);
DISPLAY 0.617021 (-1875 1725);
PAINT SKYBLUE (-1875 1725);
FORCEPROP 1 LAST VOLTAGE 16V
J 0
(-1875 1675);
DISPLAY 0.617021 (-1875 1675);
PAINT SKYBLUE (-1875 1675);
FORCEPROP 1 LAST LOCATION C3P1
J 0
(-1875 1775);
DISPLAY 0.617021 (-1875 1775);
PAINT AQUA (-1875 1775);
FORCEPROP 1 LAST MATERIAL EMPTY
J 0
(-1875 1575);
DISPLAY 0.617021 (-1875 1575);
PAINT RED (-1875 1575);
FORCEPROP 1 LAST PACK_TYPE 0402V
J 0
(-1875 1475);
DISPLAY 0.617021 (-1875 1475);
PAINT SKYBLUE (-1875 1475);
FORCEPROP 1 LAST PART_NUMBER A36096-030
J 0
(-1875 1525);
DISPLAY 0.617021 (-1875 1525);
PAINT BLUE (-1875 1525);
FORCEPROP 2 LAST CDS_LIB dev_discrete
J 0
(-1925 1675);
PAINT ORANGE (-1925 1675);
DISPLAY INVISIBLE (-1925 1675);
FORCEPROP 1 LASTPIN (-1925 1575) $PN 2
J 0
(-1915 1555);
DISPLAY 0.787234 (-1915 1555);
PAINT ORANGE (-1915 1555);
DISPLAY INVISIBLE (-1915 1555);
FORCEPROP 1 LASTPIN (-1925 1775) $PN 1
J 0
(-1915 1755);
DISPLAY 0.787234 (-1915 1755);
PAINT ORANGE (-1915 1755);
DISPLAY INVISIBLE (-1915 1755);
FORCEPROP 2 LAST CDS_LOCATION C3P1
J 0
(-1875 1775);
DISPLAY 0.617021 (-1875 1775);
PAINT AQUA (-1875 1775);
DISPLAY INVISIBLE (-1875 1775);
FORCEPROP 2 LAST BOM_COST PROC_VRD_PVCCIO_CPU0
J 0
(-1875 1825);
DISPLAY 0.723404 (-1875 1825);
PAINT ORANGE (-1875 1825);
DISPLAY INVISIBLE (-1875 1825);
FORCEPROP 1 LAST PATH I60
J 0
(-1875 1825);
DISPLAY 0.978723 (-1875 1825);
PAINT WHITE (-1875 1825);
DISPLAY INVISIBLE (-1875 1825);
FORCEPROP 2 LAST ROOM PVCCIO_CPU0
J 0
(-1875 1825);
DISPLAY 0.723404 (-1875 1825);
PAINT ORANGE (-1875 1825);
DISPLAY INVISIBLE (-1875 1825);
FORCEADD OFFPAGE..1
(-3250 1850);
FORCEPROP 2 LAST $XR0 39 
J 0
(-3471 1850);
DISPLAY 0.638298 (-3471 1850);
PAINT MONO (-3471 1850);
FORCEPROP 2 LAST ROOM VCCIN_CPU0_DECAP_VR
J 0
(-3775 1925);
PAINT ORANGE (-3775 1925);
DISPLAY INVISIBLE (-3775 1925);
FORCEPROP 2 LAST PATH I61
J 0
(-3450 1900);
DISPLAY 1.021277 (-3450 1900);
PAINT ORANGE (-3450 1900);
DISPLAY INVISIBLE (-3450 1900);
FORCEPROP 2 LAST BOM_COST PROC_VRD_VCCIN_CPU0
J 0
(-3450 1900);
PAINT MONO (-3450 1900);
DISPLAY INVISIBLE (-3450 1900);
FORCEPROP 2 LAST CDS_LIB mstr_standard
J 2
(-3250 1850);
PAINT ORANGE (-3250 1850);
DISPLAY INVISIBLE (-3250 1850);
FORCEPROP 1 LAST OFFPAGE TRUE
J 0
(-2925 1725);
DISPLAY 0.893617 (-2925 1725);
PAINT GREEN (-2925 1725);
DISPLAY INVISIBLE (-2925 1725);
FORCEPROP 1 LAST COMMENT_BODY TRUE
J 0
(-3125 1750);
DISPLAY 0.893617 (-3125 1750);
PAINT GREEN (-3125 1750);
DISPLAY INVISIBLE (-3125 1750);
FORCEADD RES..1
(-725 1150);
FORCEPROP 1 LAST LOCATION R3N20
J 0
(-775 1200);
DISPLAY 0.617021 (-775 1200);
PAINT AQUA (-775 1200);
FORCEPROP 1 LAST PART_NUMBER G21796-017
J 0
(-875 975);
DISPLAY 0.617021 (-875 975);
PAINT BLUE (-875 975);
FORCEPROP 1 LAST TOLERANCE 1%
J 0
(-900 1075);
DISPLAY 0.617021 (-900 1075);
PAINT SKYBLUE (-900 1075);
FORCEPROP 1 LAST WATTAGE 1/16W
J 2
(-700 1025);
DISPLAY 0.617021 (-700 1025);
PAINT SKYBLUE (-700 1025);
FORCEPROP 1 LAST VALUE 100.0
J 2
(-725 1075);
DISPLAY 0.617021 (-725 1075);
PAINT SKYBLUE (-725 1075);
FORCEPROP 1 LAST MATERIAL CHIP
J 0
(-675 1025);
DISPLAY 0.617021 (-675 1025);
PAINT SKYBLUE (-675 1025);
FORCEPROP 1 LAST PACK_TYPE 0402
J 0
(-675 1075);
DISPLAY 0.617021 (-675 1075);
PAINT SKYBLUE (-675 1075);
FORCEPROP 1 LASTPIN (-825 1150) $PN 1
J 0
(-813 1162);
DISPLAY 0.787234 (-813 1162);
PAINT WHITE (-813 1162);
DISPLAY INVISIBLE (-813 1162);
FORCEPROP 2 LAST CDS_LOCATION R3N20
J 0
(-775 1200);
DISPLAY 0.617021 (-775 1200);
PAINT AQUA (-775 1200);
DISPLAY INVISIBLE (-775 1200);
FORCEPROP 0 LAST BOM_COST PROC_VRD_PVCCIO_CPU0
J 0
(-775 1250);
DISPLAY 0.723404 (-775 1250);
PAINT ORANGE (-775 1250);
DISPLAY INVISIBLE (-775 1250);
FORCEPROP 2 LAST ROOM PVCCIO_CPU0
J 0
(-775 1300);
DISPLAY 0.723404 (-775 1300);
PAINT ORANGE (-775 1300);
DISPLAY INVISIBLE (-775 1300);
FORCEPROP 1 LAST PATH I68
J 0
(-775 1300);
DISPLAY 0.978723 (-775 1300);
PAINT WHITE (-775 1300);
DISPLAY INVISIBLE (-775 1300);
FORCEPROP 1 LASTPIN (-625 1150) $PN 2
J 0
(-663 1162);
DISPLAY 0.787234 (-663 1162);
PAINT WHITE (-663 1162);
DISPLAY INVISIBLE (-663 1162);
FORCEPROP 2 LAST CDS_LIB mstr_discrete
J 0
(-725 1150);
PAINT ORANGE (-725 1150);
DISPLAY INVISIBLE (-725 1150);
FORCEPROP 2 LAST $SEC 1
J 0
(-755 1370);
DISPLAY 0.680851 (-755 1370);
PAINT MONO (-755 1370);
DISPLAY INVISIBLE (-755 1370);
FORCEPROP 2 LAST CDS_SEC 1
J 0
(-755 1370);
DISPLAY 1.021277 (-755 1370);
PAINT ORANGE (-755 1370);
DISPLAY INVISIBLE (-755 1370);
FORCEADD GND..1
(-450 925);
FORCEPROP 3 LASTPIN (-450 975) SIG_NAME GND\g
J 0
(-440 985);
DISPLAY 0.659574 (-440 985);
PAINT MONO (-440 985);
DISPLAY INVISIBLE (-440 985);
FORCEPROP 1 LAST VOLTAGE 0
J 0
(-450 925);
DISPLAY 0.723404 (-450 925);
PAINT SKYBLUE (-450 925);
DISPLAY INVISIBLE (-450 925);
FORCEPROP 1 LAST PATH I69
J 0
(-375 925);
DISPLAY 0.872340 (-375 925);
PAINT AQUA (-375 925);
DISPLAY INVISIBLE (-375 925);
FORCEPROP 1 LAST SIZE 1B
J 0
(-375 875);
DISPLAY 0.638298 (-375 875);
PAINT GREEN (-375 875);
DISPLAY INVISIBLE (-375 875);
FORCEPROP 2 LAST CDS_LIB mstr_symbols
J 0
(-450 925);
PAINT ORANGE (-450 925);
DISPLAY INVISIBLE (-450 925);
FORCEPROP 2 LAST BOM_COST MEM_VRD_PVCCIO_CPU0
J 0
(-950 1000);
DISPLAY 0.723404 (-950 1000);
PAINT ORANGE (-950 1000);
DISPLAY INVISIBLE (-950 1000);
FORCEPROP 2 LAST ROOM PVCCIO_CPU0
J 0
(-750 1000);
DISPLAY 0.723404 (-750 1000);
PAINT ORANGE (-750 1000);
DISPLAY INVISIBLE (-750 1000);
FORCEPROP 1 LAST BODY_TYPE PLUMBING
J 0
(-495 882);
DISPLAY 0.340426 (-495 882);
PAINT GREEN (-495 882);
DISPLAY INVISIBLE (-495 882);
FORCEPROP 1 LAST HDL_POWER GND
J 0
(-450 1075);
DISPLAY 0.638298 (-450 1075);
PAINT GREEN (-450 1075);
DISPLAY INVISIBLE (-450 1075);
FORCEADD OFFPAGE..2
(-225 1400);
FORCEPROP 2 LAST $XR0 211 
J 0
(-36 1400);
DISPLAY 0.638298 (-36 1400);
PAINT MONO (-36 1400);
FORCEPROP 2 LAST CDS_LIB mstr_standard
J 0
(-225 1400);
PAINT ORANGE (-225 1400);
DISPLAY INVISIBLE (-225 1400);
FORCEPROP 2 LAST PATH I70
J 0
(-25 1450);
DISPLAY 1.021277 (-25 1450);
PAINT ORANGE (-25 1450);
DISPLAY INVISIBLE (-25 1450);
FORCEPROP 2 LAST ROOM PVCCIO_CPU0
J 0
(50 1425);
DISPLAY 0.617021 (50 1425);
PAINT ORANGE (50 1425);
DISPLAY INVISIBLE (50 1425);
FORCEPROP 1 LAST OFFPAGE TRUE
J 0
(100 1275);
DISPLAY 0.872340 (100 1275);
PAINT GREEN (100 1275);
DISPLAY INVISIBLE (100 1275);
FORCEPROP 1 LAST COMMENT_BODY TRUE
J 0
(-270 1305);
DISPLAY 0.872340 (-270 1305);
PAINT GREEN (-270 1305);
DISPLAY INVISIBLE (-270 1305);
FORCEADD RES..1
(-725 2325);
FORCEPROP 1 LAST TOLERANCE 1%
J 0
(-900 2250);
DISPLAY 0.617021 (-900 2250);
PAINT SKYBLUE (-900 2250);
FORCEPROP 1 LAST PART_NUMBER G21796-017
J 0
(-875 2150);
DISPLAY 0.617021 (-875 2150);
PAINT BLUE (-875 2150);
FORCEPROP 1 LAST WATTAGE 1/16W
J 2
(-700 2200);
DISPLAY 0.617021 (-700 2200);
PAINT SKYBLUE (-700 2200);
FORCEPROP 1 LAST MATERIAL CHIP
J 0
(-675 2200);
DISPLAY 0.617021 (-675 2200);
PAINT SKYBLUE (-675 2200);
FORCEPROP 1 LAST VALUE 100.0
J 2
(-725 2250);
DISPLAY 0.617021 (-725 2250);
PAINT SKYBLUE (-725 2250);
FORCEPROP 1 LAST LOCATION R3N21
J 0
(-775 2375);
DISPLAY 0.617021 (-775 2375);
PAINT AQUA (-775 2375);
FORCEPROP 1 LAST PACK_TYPE 0402
J 0
(-675 2250);
DISPLAY 0.617021 (-675 2250);
PAINT SKYBLUE (-675 2250);
FORCEPROP 2 LAST CDS_LOCATION R3N21
J 0
(-775 2375);
DISPLAY 0.978723 (-775 2375);
PAINT AQUA (-775 2375);
DISPLAY INVISIBLE (-775 2375);
FORCEPROP 0 LAST BOM_COST PROC_VRD_PVCCIO_CPU0
J 0
(-775 2425);
DISPLAY 0.723404 (-775 2425);
PAINT ORANGE (-775 2425);
DISPLAY INVISIBLE (-775 2425);
FORCEPROP 2 LAST CDS_LOCATION R3N21
J 0
(-775 2375);
DISPLAY 0.617021 (-775 2375);
PAINT AQUA (-775 2375);
DISPLAY INVISIBLE (-775 2375);
FORCEPROP 1 LAST PATH I74
J 0
(-775 2475);
DISPLAY 0.978723 (-775 2475);
PAINT WHITE (-775 2475);
DISPLAY INVISIBLE (-775 2475);
FORCEPROP 2 LAST ROOM PVCCIO_CPU0
J 0
(-775 2475);
DISPLAY 0.723404 (-775 2475);
PAINT ORANGE (-775 2475);
DISPLAY INVISIBLE (-775 2475);
FORCEPROP 1 LASTPIN (-825 2325) $PN 1
J 0
(-813 2337);
DISPLAY 0.787234 (-813 2337);
PAINT WHITE (-813 2337);
DISPLAY INVISIBLE (-813 2337);
FORCEPROP 1 LAST LOCATION R3N21
J 0
(-775 2375);
DISPLAY 0.978723 (-775 2375);
PAINT AQUA (-775 2375);
DISPLAY INVISIBLE (-775 2375);
FORCEPROP 2 LAST CDS_LIB mstr_discrete
J 0
(-725 2325);
PAINT ORANGE (-725 2325);
DISPLAY INVISIBLE (-725 2325);
FORCEPROP 1 LASTPIN (-625 2325) $PN 2
J 0
(-663 2337);
DISPLAY 0.787234 (-663 2337);
PAINT WHITE (-663 2337);
DISPLAY INVISIBLE (-663 2337);
FORCEPROP 2 LAST CDS_SEC 1
J 0
(-761 2545);
DISPLAY 1.021277 (-761 2545);
PAINT ORANGE (-761 2545);
DISPLAY INVISIBLE (-761 2545);
FORCEPROP 2 LAST $SEC 1
J 0
(-761 2545);
DISPLAY 0.680851 (-761 2545);
PAINT MONO (-761 2545);
DISPLAY INVISIBLE (-761 2545);
FORCEADD PVCCIO_CPU0..1
(-500 2525);
FORCEPROP 3 LASTPIN (-500 2475) SIG_NAME PVCCIO_CPU0\g
J 0
(-490 2485);
DISPLAY 0.659574 (-490 2485);
PAINT MONO (-490 2485);
DISPLAY INVISIBLE (-490 2485);
FORCEPROP 1 LAST HDL_POWER PVCCIO_CPU0
J 1
(-500 2575);
DISPLAY 0.872340 (-500 2575);
PAINT GREEN (-500 2575);
DISPLAY INVISIBLE (-500 2575);
FORCEPROP 1 LAST BODY_TYPE PLUMBING
J 0
(-545 2482);
DISPLAY 0.340426 (-545 2482);
PAINT GREEN (-545 2482);
DISPLAY INVISIBLE (-545 2482);
FORCEPROP 2 LAST CDS_LIB mstr_symbols
J 0
(-500 2525);
PAINT ORANGE (-500 2525);
DISPLAY INVISIBLE (-500 2525);
FORCEPROP 1 LAST PATH I75
J 0
(-450 2550);
DISPLAY 0.872340 (-450 2550);
PAINT AQUA (-450 2550);
DISPLAY INVISIBLE (-450 2550);
FORCEPROP 1 LAST VOLTAGE 1.1V
J 0
(-545 2482);
DISPLAY 0.340426 (-545 2482);
PAINT SKYBLUE (-545 2482);
DISPLAY INVISIBLE (-545 2482);
FORCEADD OFFPAGE..2
(-250 1850);
FORCEPROP 2 LAST $XR0 211 
J 0
(-61 1850);
DISPLAY 0.638298 (-61 1850);
PAINT MONO (-61 1850);
FORCEPROP 2 LAST CDS_LIB mstr_standard
J 0
(-250 1850);
PAINT ORANGE (-250 1850);
DISPLAY INVISIBLE (-250 1850);
FORCEPROP 2 LAST PATH I76
J 0
(-50 1900);
DISPLAY 1.021277 (-50 1900);
PAINT ORANGE (-50 1900);
DISPLAY INVISIBLE (-50 1900);
FORCEPROP 2 LAST ROOM PVCCIO_CPU0
J 0
(25 1875);
DISPLAY 0.617021 (25 1875);
PAINT ORANGE (25 1875);
DISPLAY INVISIBLE (25 1875);
FORCEPROP 1 LAST OFFPAGE TRUE
J 0
(75 1725);
DISPLAY 0.872340 (75 1725);
PAINT GREEN (75 1725);
DISPLAY INVISIBLE (75 1725);
FORCEPROP 1 LAST COMMENT_BODY TRUE
J 0
(-295 1755);
DISPLAY 0.872340 (-295 1755);
PAINT GREEN (-295 1755);
DISPLAY INVISIBLE (-295 1755);
FORCEADD CAP_A..1
(3225 3275);
FORCEPROP 1 LAST PACK_TYPE 0603V
J 0
(3275 3075);
DISPLAY 0.617021 (3275 3075);
PAINT SKYBLUE (3275 3075);
FORCEPROP 1 LASTPIN (3225 3175) $PN 2
J 0
(3235 3155);
DISPLAY 0.617021 (3235 3155);
PAINT ORANGE (3235 3155);
FORCEPROP 1 LASTPIN (3225 3375) $PN 1
J 0
(3235 3355);
DISPLAY 0.617021 (3235 3355);
PAINT ORANGE (3235 3355);
FORCEPROP 1 LAST TOLERANCE 20%
J 0
(3275 3225);
DISPLAY 0.617021 (3275 3225);
PAINT SKYBLUE (3275 3225);
FORCEPROP 1 LAST VOLTAGE 4V
J 0
(3275 3275);
DISPLAY 0.617021 (3275 3275);
PAINT SKYBLUE (3275 3275);
FORCEPROP 1 LAST MATERIAL X6S
J 0
(3275 3175);
DISPLAY 0.617021 (3275 3175);
PAINT SKYBLUE (3275 3175);
FORCEPROP 1 LAST LOCATION C7C10
J 0
(3275 3375);
DISPLAY 0.617021 (3275 3375);
PAINT AQUA (3275 3375);
FORCEPROP 1 LAST VALUE 22.0UF
J 0
(3275 3325);
DISPLAY 0.617021 (3275 3325);
PAINT SKYBLUE (3275 3325);
FORCEPROP 1 LAST PART_NUMBER E15431-004
J 0
(3275 3125);
DISPLAY 0.617021 (3275 3125);
PAINT BLUE (3275 3125);
FORCEPROP 2 LAST CDS_LIB dev_discrete
J 0
(3225 3275);
PAINT ORANGE (3225 3275);
DISPLAY INVISIBLE (3225 3275);
FORCEPROP 2 LAST SEC 1
J 0
(3275 3475);
DISPLAY 0.680851 (3275 3475);
PAINT MONO (3275 3475);
DISPLAY INVISIBLE (3275 3475);
FORCEPROP 2 LAST SEC_TYPE 0603V
J 0
(3275 3475);
DISPLAY 1.021277 (3275 3475);
PAINT ORANGE (3275 3475);
DISPLAY INVISIBLE (3275 3475);
FORCEPROP 1 LAST PATH I77
J 0
(3275 3425);
DISPLAY 0.978723 (3275 3425);
PAINT WHITE (3275 3425);
DISPLAY INVISIBLE (3275 3425);
FORCEPROP 2 LAST CDS_SEC 1
J 0
(3275 3425);
PAINT ORANGE (3275 3425);
DISPLAY INVISIBLE (3275 3425);
FORCEPROP 2 LAST CDS_LOCATION C7C10
J 0
(3275 3375);
DISPLAY 0.617021 (3275 3375);
PAINT AQUA (3275 3375);
DISPLAY INVISIBLE (3275 3375);
FORCEADD RES..2
(3600 3275);
FORCEPROP 1 LASTPIN (3600 3175) $PN 2
J 0
(3605 3185);
DISPLAY 0.617021 (3605 3185);
PAINT ORANGE (3605 3185);
FORCEPROP 1 LAST TOLERANCE 1.0%
J 0
(3645 3300);
DISPLAY 0.617021 (3645 3300);
PAINT SKYBLUE (3645 3300);
FORCEPROP 1 LAST PACK_TYPE 0402
J 0
(3640 3100);
DISPLAY 0.617021 (3640 3100);
PAINT SKYBLUE (3640 3100);
FORCEPROP 1 LAST MATERIAL CHIP
J 0
(3640 3200);
DISPLAY 0.617021 (3640 3200);
PAINT SKYBLUE (3640 3200);
FORCEPROP 1 LAST WATTAGE 1/16W
J 0
(3640 3250);
DISPLAY 0.617021 (3640 3250);
PAINT SKYBLUE (3640 3250);
FORCEPROP 1 LASTPIN (3600 3375) $PN 1
J 0
(3605 3337);
DISPLAY 0.617021 (3605 3337);
PAINT ORANGE (3605 3337);
FORCEPROP 1 LAST LOCATION R7C3
J 0
(3645 3400);
DISPLAY 0.617021 (3645 3400);
PAINT AQUA (3645 3400);
FORCEPROP 1 LAST VALUE 51.1
J 0
(3645 3350);
DISPLAY 0.617021 (3645 3350);
PAINT SKYBLUE (3645 3350);
FORCEPROP 1 LAST PART_NUMBER G21796-208
J 0
(3640 3150);
DISPLAY 0.617021 (3640 3150);
PAINT BLUE (3640 3150);
FORCEPROP 2 LAST CDS_LIB mstr_discrete
J 0
(3600 3275);
PAINT ORANGE (3600 3275);
DISPLAY INVISIBLE (3600 3275);
FORCEPROP 2 LAST CDS_LOCATION R7C3
J 0
(3645 3400);
DISPLAY 0.617021 (3645 3400);
PAINT AQUA (3645 3400);
DISPLAY INVISIBLE (3645 3400);
FORCEPROP 1 LAST PATH I78
J 0
(3650 3450);
DISPLAY 0.978723 (3650 3450);
PAINT WHITE (3650 3450);
DISPLAY INVISIBLE (3650 3450);
FORCEPROP 2 LAST SEC_TYPE 0402
J 0
(3650 3500);
DISPLAY 1.021277 (3650 3500);
PAINT ORANGE (3650 3500);
DISPLAY INVISIBLE (3650 3500);
FORCEPROP 2 LAST SEC 1
J 0
(3650 3500);
DISPLAY 0.680851 (3650 3500);
PAINT MONO (3650 3500);
DISPLAY INVISIBLE (3650 3500);
FORCEADD VCC_CORE..1
(-3150 4575);
FORCEPROP 3 LASTPIN (-3150 4525) SIG_NAME VR_FET_SW_P12V_STBY_PVCCIO_CPU0\g
J 0
(-3140 4535);
DISPLAY 0.659574 (-3140 4535);
PAINT MONO (-3140 4535);
DISPLAY INVISIBLE (-3140 4535);
FORCEPROP 1 LAST HDL_POWER VR_FET_SW_P12V_STBY_PVCCIO_CPU0
J 1
(-3100 4625);
DISPLAY 0.617021 (-3100 4625);
PAINT GREEN (-3100 4625);
FORCEPROP 1 LAST PATH I79
J 0
(-3100 4600);
DISPLAY 0.872340 (-3100 4600);
PAINT AQUA (-3100 4600);
DISPLAY INVISIBLE (-3100 4600);
FORCEPROP 2 LAST CDS_LIB mstr_symbols
J 0
(-3150 4575);
PAINT MONO (-3150 4575);
DISPLAY INVISIBLE (-3150 4575);
FORCEADD VCC_CORE..1
(1025 2550);
FORCEPROP 3 LASTPIN (1025 2500) SIG_NAME VR_FET_SW_P12V_STBY_PVCCIO_CPU0\g
J 0
(1035 2510);
DISPLAY 0.659574 (1035 2510);
PAINT MONO (1035 2510);
DISPLAY INVISIBLE (1035 2510);
FORCEPROP 1 LAST HDL_POWER VR_FET_SW_P12V_STBY_PVCCIO_CPU0
J 1
(1075 2600);
DISPLAY 0.617021 (1075 2600);
PAINT GREEN (1075 2600);
FORCEPROP 1 LAST PATH I80
J 0
(1075 2575);
DISPLAY 0.872340 (1075 2575);
PAINT AQUA (1075 2575);
DISPLAY INVISIBLE (1075 2575);
FORCEPROP 2 LAST CDS_LIB mstr_symbols
J 0
(1025 2550);
PAINT MONO (1025 2550);
DISPLAY INVISIBLE (1025 2550);
FORCEADD PVCCIO_CPU0..1
(3375 2675);
FORCEPROP 3 LASTPIN (3375 2625) SIG_NAME PVCCIO_CPU0\g
J 0
(3385 2635);
DISPLAY 0.659574 (3385 2635);
PAINT MONO (3385 2635);
DISPLAY INVISIBLE (3385 2635);
FORCEPROP 1 LAST VOLTAGE 1.1V
J 0
(3330 2632);
DISPLAY 0.340426 (3330 2632);
PAINT SKYBLUE (3330 2632);
DISPLAY INVISIBLE (3330 2632);
FORCEPROP 2 LAST CDS_LIB mstr_symbols
J 0
(3375 2675);
PAINT ORANGE (3375 2675);
DISPLAY INVISIBLE (3375 2675);
FORCEPROP 1 LAST PATH I82
J 0
(3425 2700);
DISPLAY 0.872340 (3425 2700);
PAINT AQUA (3425 2700);
DISPLAY INVISIBLE (3425 2700);
FORCEPROP 1 LAST BODY_TYPE PLUMBING
J 0
(3330 2632);
DISPLAY 0.340426 (3330 2632);
PAINT GREEN (3330 2632);
DISPLAY INVISIBLE (3330 2632);
FORCEPROP 1 LAST HDL_POWER PVCCIO_CPU0
J 1
(3375 2725);
DISPLAY 0.872340 (3375 2725);
PAINT GREEN (3375 2725);
DISPLAY INVISIBLE (3375 2725);
FORCEADD DNS..2
(-1920 1670);
PAINT RED (-1920 1670);
FORCEPROP 2 LAST CDS_LIB mstr_misc
J 0
(-1920 1670);
PAINT ORANGE (-1920 1670);
DISPLAY INVISIBLE (-1920 1670);
FORCEPROP 1 LAST COMMENT_BODY TRUE
R 1
J 0
(-1845 1445);
DISPLAY 0.872340 (-1845 1445);
PAINT GREEN (-1845 1445);
DISPLAY INVISIBLE (-1845 1445);
FORCEADD DNS..3
(-1295 1845);
PAINT RED (-1295 1845);
FORCEPROP 2 LAST CDS_LIB mstr_misc
J 0
(-1295 1845);
PAINT ORANGE (-1295 1845);
DISPLAY INVISIBLE (-1295 1845);
FORCEPROP 1 LAST COMMENT_BODY TRUE
R 1
J 0
(-1220 1620);
DISPLAY 0.872340 (-1220 1620);
PAINT GREEN (-1220 1620);
DISPLAY INVISIBLE (-1220 1620);
FORCEADD DNS..2
(3105 3945);
PAINT RED (3105 3945);
FORCEPROP 2 LAST CDS_LIB mstr_misc
J 0
(3105 3945);
PAINT ORANGE (3105 3945);
DISPLAY INVISIBLE (3105 3945);
FORCEPROP 1 LAST COMMENT_BODY TRUE
R 1
J 0
(3180 3720);
DISPLAY 0.872340 (3180 3720);
PAINT GREEN (3180 3720);
DISPLAY INVISIBLE (3180 3720);
FORCEADD DNS..3
(-1295 1395);
PAINT RED (-1295 1395);
FORCEPROP 2 LAST CDS_LIB mstr_misc
J 0
(-1295 1395);
PAINT ORANGE (-1295 1395);
DISPLAY INVISIBLE (-1295 1395);
FORCEPROP 1 LAST COMMENT_BODY TRUE
R 1
J 0
(-1220 1170);
DISPLAY 0.872340 (-1220 1170);
PAINT GREEN (-1220 1170);
DISPLAY INVISIBLE (-1220 1170);
FORCEADD DESIGN_NOTE..1
(-3225 2875);
PAINT PURPLE (-3225 2875);
FORCEPROP 2 LAST CDS_LIB mstr_symbols
J 0
(-3225 2875);
PAINT ORANGE (-3225 2875);
DISPLAY INVISIBLE (-3225 2875);
FORCEPROP 2 LAST BOM_COST SM_CONTROLLER
J 0
(-3425 2825);
PAINT MONO (-3425 2825);
DISPLAY INVISIBLE (-3425 2825);
FORCEPROP 2 LAST ROOM PVCCIN_CPU0_VR
J 0
(-3425 2825);
PAINT MONO (-3425 2825);
DISPLAY INVISIBLE (-3425 2825);
FORCEPROP 1 LAST COMMENT_BODY TRUE
J 0
(-3200 2975);
DISPLAY 1.319149 (-3200 2975);
PAINT GREEN (-3200 2975);
DISPLAY INVISIBLE (-3200 2975);
FORCEADD INTEL_CORP_BPAGE..1
(4275 100);
FORCEPROP 1 LAST CDS_CON_LAST_MODIFIED Tue Dec 01 11:52:24 2015
J 0
(2850 425);
PAINT ORANGE (2850 425);
DISPLAY INVISIBLE (2850 425);
FORCEPROP 1 LAST CUSTOM_TXT_CDS <CURRENT_DESIGN_SHEET> OF <TOTAL_DESIGN_SHEETS>
J 0
(3775 125);
PAINT GREEN (3775 125);
FORCEPROP 1 LAST CUSTOM_TXT_CDS <CON_LAST_MODIFIED>
J 0
(2350 450);
PAINT GREEN (2350 450);
FORCEPROP 2 LAST CUSTOM_TXT_CDS <XR_PAGE_TITLE>
J 0
(-3615 5350);
DISPLAY 0.638298 (-3615 5350);
PAINT PINK (-3615 5350);
DISPLAY INVISIBLE (-3615 5350);
FORCEPROP 1 LAST SCH_ADDRESS1 2200 Mission College Blvd.
J 0
(300 225);
DISPLAY 0.617021 (300 225);
PAINT GREEN (300 225);
FORCEPROP 1 LAST SCH_ADDRESS3 Santa Clara, CA 95052-8119
J 0
(300 125);
DISPLAY 0.617021 (300 125);
PAINT GREEN (300 125);
FORCEPROP 1 LAST SCH_TITLE PVCCIO CPU0 (2 OF 2)
J 0
(-3675 150);
DISPLAY 1.212766 (-3675 150);
PAINT ORANGE (-3675 150);
FORCEPROP 1 LAST SCH_ADDRESS2 P.O. BOX 58119
J 0
(300 175);
DISPLAY 0.617021 (300 175);
PAINT GREEN (300 175);
FORCEPROP 1 LAST SCH_REV 2.420
J 0
(4025 250);
DISPLAY 0.978723 (4025 250);
PAINT YELLOW (4025 250);
FORCEPROP 1 LAST SCH_DEPT BESD
J 1
(-175 200);
DISPLAY 1.212766 (-175 200);
PAINT YELLOW (-175 200);
FORCEPROP 1 LAST SCH_NUMBER H4694802
J 0
(2975 250);
DISPLAY 1.212766 (2975 250);
PAINT YELLOW (2975 250);
FORCEPROP 2 LAST PAGE_BORDER TRUE
J 0
(-3615 5350);
DISPLAY 0.638298 (-3615 5350);
PAINT PINK (-3615 5350);
DISPLAY INVISIBLE (-3615 5350);
FORCEPROP 2 LAST CDS_LIB mstr_symbols
J 0
(4275 100);
PAINT MONO (4275 100);
DISPLAY INVISIBLE (4275 100);
FORCEPROP 1 LAST COMMENT_BODY TRUE
J 0
(4287 112);
DISPLAY 0.468085 (4287 112);
PAINT GREEN (4287 112);
DISPLAY INVISIBLE (4287 112);
FORCEPROP 2 LAST CDS_XR_PAGE_TITLE CR-212 : @BASEBOARD_FAB2_LIB.BASEBOARD_FAB2(SCH_1):PAGE212
J 0
(-3615 5350);
DISPLAY 0.638298 (-3615 5350);
PAINT PINK (-3615 5350);
DISPLAY INVISIBLE (-3615 5350);
WIRE 16 -1 (3100 3850)(3100 3750);
WIRE 16 -1 (25 3175)(25 3075);
WIRE 16 -1 (1950 3700)(1950 3625);
WIRE 16 -1 (2050 2875)(2050 2800);
WIRE 16 -1 (2550 2300)(2550 2150);
WIRE 16 -1 (2550 2150)(2950 2150);
WIRE 16 -1 (2950 2300)(2950 2150);
WIRE 16 -1 (2950 2150)(3375 2150);
WIRE 16 -1 (3375 2300)(3375 2150);
WIRE 16 -1 (3375 2150)(3375 2100);
WIRE 16 -1 (325 3925)(100 3925);
WIRE 16 -1 (100 3925)(100 2675);
WIRE 16 -1 (100 2675)(2725 2675);
WIRE 16 -1 (2725 2675)(2725 3475);
WIRE 16 -1 (2575 3475)(2725 3475);
WIRE 16 -1 (2725 3475)(2925 3475);
WIRE 16 -1 (2925 3375)(2925 3475);
WIRE 16 -1 (3225 3475)(2925 3475);
WIRE 16 -1 (3225 3375)(3225 3475);
WIRE 16 -1 (3600 3475)(3225 3475);
WIRE 16 -1 (3600 3375)(3600 3475);
WIRE 16 -1 (3600 3475)(3600 3550);
WIRE 16 -1 (3600 3175)(3600 3050);
WIRE 16 -1 (3600 3050)(3225 3050);
WIRE 16 -1 (3225 3175)(3225 3050);
WIRE 16 -1 (3225 3050)(2925 3050);
WIRE 16 -1 (2925 3175)(2925 3050);
WIRE 16 -1 (2925 3000)(2925 3050);
WIRE 16 -1 (1475 3375)(1325 3375);
WIRE 16 -1 (1475 3325)(1475 3375);
WIRE 16 -1 (1325 3325)(1475 3325);
WIRE 16 -1 (1475 3275)(1475 3325);
WIRE 16 -1 (1325 3275)(1475 3275);
WIRE 16 -1 (1475 3225)(1475 3275);
WIRE 16 -1 (1325 3225)(1475 3225);
WIRE 16 -1 (1475 3075)(1475 3225);
WIRE 16 -1 (-1275 3950)(-1275 3775);
WIRE 16 -1 (-1275 3775)(-1425 3775);
WIRE 16 -1 (-1425 3950)(-1425 3775);
WIRE 16 -1 (-1975 3775)(-1425 3775);
WIRE 16 -1 (-1975 3900)(-1975 3775);
WIRE 16 -1 (-1975 3775)(-2200 3775);
WIRE 16 -1 (-2200 3900)(-2200 3775);
WIRE 16 -1 (-2200 3775)(-2450 3775);
WIRE 16 -1 (-2450 3925)(-2450 3775);
WIRE 16 -1 (-2450 3775)(-2675 3775);
WIRE 16 -1 (-2675 3900)(-2675 3775);
WIRE 16 -1 (-2675 3775)(-2900 3775);
WIRE 16 -1 (-2900 3950)(-2900 3775);
WIRE 16 -1 (-2900 3775)(-3150 3775);
WIRE 16 -1 (-3150 3950)(-3150 3775);
WIRE 16 -1 (-3150 3725)(-3150 3775);
WIRE 16 -1 (1400 2125)(1400 2025);
WIRE 16 -1 (825 2100)(825 2025);
WIRE 16 -1 (-50 2450)(225 2450);
WIRE 16 -1 (-50 2500)(-50 2450);
WIRE 16 -1 (325 4025)(175 4025);
WIRE 16 -1 (175 4025)(175 4125);
WIRE 16 -1 (175 4125)(325 4125);
WIRE 16 -1 (-425 4125)(175 4125);
WIRE 16 -1 (-425 4575)(-425 4125);
WIRE 16 -1 (-425 4575)(-1275 4575);
WIRE 16 -1 (-425 4575)(-425 4650);
WIRE 16 -1 (-1275 4575)(-1425 4575);
WIRE 16 -1 (-1275 4150)(-1275 4575);
WIRE 16 -1 (-1425 4150)(-1425 4575);
WIRE 16 -1 (-1425 4575)(-1625 4575);
WIRE 16 -1 (-450 1150)(-625 1150);
WIRE 16 -1 (-450 975)(-450 1150);
WIRE 16 -1 (-500 2475)(-500 2325);
WIRE 16 -1 (-500 2325)(-625 2325);
WIRE 16 -1 (325 4275)(100 4275);
WIRE 16 -1 (100 4275)(100 4225);
WIRE 16 -1 (325 4225)(100 4225);
WIRE 16 -1 (100 4225)(-2200 4225);
WIRE 16 -1 (-2200 4100)(-2200 4225);
WIRE 16 -1 (-2200 4225)(-2450 4225);
WIRE 16 -1 (-2450 4125)(-2450 4225);
WIRE 16 -1 (-2450 4225)(-2675 4225);
WIRE 16 -1 (-2675 4100)(-2675 4225);
WIRE 16 -1 (-2675 4225)(-2900 4225);
WIRE 16 -1 (-2900 4150)(-2900 4225);
WIRE 16 -1 (-2900 4225)(-3150 4225);
WIRE 16 -1 (-3150 4150)(-3150 4225);
WIRE 16 -1 (-3150 4525)(-3150 4225);
WIRE 16 -1 (1400 2325)(1400 2450);
WIRE 16 -1 (1025 2450)(1400 2450);
WIRE 16 -1 (825 2450)(1025 2450);
FORCEPROP 0 LAST VOLTAGE 12
J 0
(925 2500);
DISPLAY 1.021277 (925 2500);
PAINT SKYBLUE (925 2500);
DISPLAY INVISIBLE (925 2500);
WIRE 16 -1 (1025 2500)(1025 2450);
WIRE 16 -1 (825 2300)(825 2450);
WIRE 16 -1 (425 2450)(825 2450);
WIRE 16 -1 (2550 2500)(2550 2575);
WIRE 16 -1 (2550 2575)(2950 2575);
WIRE 16 -1 (2950 2500)(2950 2575);
WIRE 16 -1 (2950 2575)(3375 2575);
WIRE 16 -1 (3375 2500)(3375 2575);
WIRE 16 -1 (3375 2575)(3375 2625);
WIRE 16 -1 (-1975 4325)(325 4325);
FORCEPROP 0 LAST VOLTAGE 5
J 0
(-250 4400);
DISPLAY 1.021277 (-250 4400);
PAINT SKYBLUE (-250 4400);
DISPLAY INVISIBLE (-250 4400);
FORCEPROP 2 LAST SIG_NAME VR_PVCCIO_CPU0_PH1_VCIN
J 0
(-1935 4335);
DISPLAY 0.617021 (-1935 4335);
PAINT ORANGE (-1935 4335);
FORCEPROP 2 LASTPROP $XRERR UNIQUE?
J 0
(-2175 4335);
DISPLAY 0.638298 (-2175 4335);
PAINT MONO (-2175 4335);
DISPLAY INVISIBLE (-2175 4335);
WIRE 16 -1 (-1975 4575)(-1975 4325);
WIRE 16 -1 (-1975 4100)(-1975 4325);
WIRE 16 -1 (-1975 4575)(-1825 4575);
WIRE 16 -1 (-850 3575)(-100 3575);
FORCEPROP 0 LAST SIG_NAME VR_PVCCIO_CPU0_PH1_BOOT_R
J 0
(-735 3585);
DISPLAY 0.617021 (-735 3585);
PAINT ORANGE (-735 3585);
FORCEPROP 2 LASTPROP $XRERR UNIQUE?
J 0
(-975 3585);
DISPLAY 0.638298 (-975 3585);
PAINT MONO (-975 3585);
DISPLAY INVISIBLE (-975 3585);
WIRE 16 -1 (-100 3475)(-100 3575);
WIRE 16 -1 (-100 3475)(325 3475);
WIRE 16 -1 (-1050 3575)(-2025 3575);
FORCEPROP 0 LAST SIG_NAME VR_PVCCIO_CPU0_PH1_BOOT
J 0
(-2010 3585);
DISPLAY 0.617021 (-2010 3585);
PAINT ORANGE (-2010 3585);
FORCEPROP 2 LASTPROP $XRERR UNIQUE?
J 0
(-2250 3585);
DISPLAY 0.638298 (-2250 3585);
PAINT MONO (-2250 3585);
DISPLAY INVISIBLE (-2250 3585);
WIRE 16 -1 (-2025 3525)(-2025 3575);
WIRE 16 2175 (-2350 3625)(-1400 3625);
WIRE 16 2175 (-2350 3625)(-2350 3200);
WIRE 16 2175 (-1400 3625)(-1400 3200);
WIRE 16 2175 (-2350 3200)(-1400 3200);
WIRE 16 -1 (-3175 1400)(-2475 1400);
FORCEPROP 2 LAST SIG_NAME VSENSE_PVCCIO_CPU0_SKT_VRTN
J 0
(-3185 1410);
DISPLAY 0.617021 (-3185 1410);
PAINT ORANGE (-3185 1410);
WIRE 16 -1 (-2475 1400)(-2475 1600);
WIRE 16 -1 (-2475 1600)(-2075 1600);
WIRE 16 -1 (-2075 1600)(-2075 1400);
WIRE 16 -1 (-1925 1400)(-2075 1400);
WIRE 16 -1 (-1925 1400)(-1450 1400);
WIRE 16 -1 (-1925 1400)(-1925 1575);
WIRE 16 2175 (-2100 1850)(-2425 1850);
WIRE 16 2175 (-2100 1425)(-2100 1850);
WIRE 16 2175 (-2425 1850)(-2425 1425);
WIRE 16 2175 (-2425 1425)(-2100 1425);
WIRE 16 -1 (-2475 1850)(-2475 1650);
WIRE 16 -1 (-2475 1850)(-3200 1850);
FORCEPROP 2 LAST SIG_NAME VSENSE_PVCCIO_CPU0_SKT_VSEN
J 0
(-3185 1861);
DISPLAY 0.617021 (-3185 1861);
PAINT ORANGE (-3185 1861);
WIRE 16 -1 (-2475 1650)(-2075 1650);
WIRE 16 -1 (-2075 1650)(-2075 1850);
WIRE 16 -1 (-1925 1850)(-2075 1850);
WIRE 16 -1 (-1925 1850)(-1450 1850);
WIRE 16 -1 (-1925 1775)(-1925 1850);
WIRE 16 2175 (-1000 1150)(-1000 2000);
WIRE 16 2175 (-1625 1150)(-1000 1150);
WIRE 16 2175 (-1000 2000)(-1625 2000);
WIRE 16 2175 (-1625 2000)(-1625 1150);
WIRE 16 -1 (-2025 3275)(-100 3275);
FORCEPROP 0 LAST VOLTAGE 5
J 0
(-1975 3350);
DISPLAY 1.021277 (-1975 3350);
PAINT SKYBLUE (-1975 3350);
DISPLAY INVISIBLE (-1975 3350);
FORCEPROP 2 LAST SIG_NAME VR_PVCCIO_CPU0_PH1_PHASE
J 0
(-1985 3285);
DISPLAY 0.617021 (-1985 3285);
PAINT ORANGE (-1985 3285);
FORCEPROP 2 LASTPROP $XRERR UNIQUE?
J 0
(-2225 3285);
DISPLAY 0.638298 (-2225 3285);
PAINT MONO (-2225 3285);
DISPLAY INVISIBLE (-2225 3285);
WIRE 16 -1 (-2025 3275)(-2025 3325);
WIRE 16 -1 (-100 3275)(-100 3425);
WIRE 16 -1 (-100 3425)(325 3425);
WIRE 3 2175 (-1100 3650)(-750 3650);
WIRE 3 2175 (-1100 3650)(-1100 3400);
WIRE 3 2175 (-750 3650)(-750 3400);
WIRE 3 2175 (-1100 3400)(-750 3400);
WIRE 16 -1 (-275 1400)(-950 1400);
FORCEPROP 2 LAST SIG_NAME VSENSE_PVCCIO_CPU0_AVSN
J 0
(-937 1413);
DISPLAY 0.617021 (-937 1413);
PAINT ORANGE (-937 1413);
WIRE 16 -1 (-950 1150)(-950 1400);
WIRE 16 -1 (-1150 1400)(-950 1400);
WIRE 16 -1 (-825 1150)(-950 1150);
WIRE 16 -1 (-825 2325)(-950 2325);
WIRE 16 -1 (-950 2325)(-950 1850);
WIRE 16 -1 (-300 1850)(-950 1850);
FORCEPROP 2 LAST SIG_NAME VSENSE_PVCCIO_CPU0_AVSP
J 0
(-925 1863);
DISPLAY 0.617021 (-925 1863);
PAINT ORANGE (-925 1863);
WIRE 16 -1 (-950 1850)(-1150 1850);
WIRE 3 2175 (1850 3550)(2325 3550);
WIRE 3 2175 (1850 4025)(1850 3550);
WIRE 3 2175 (2325 4025)(2325 3550);
WIRE 3 2175 (1850 4025)(2325 4025);
WIRE 3 2175 (1850 3525)(2325 3525);
WIRE 3 2175 (1850 3525)(1850 2700);
WIRE 3 2175 (2325 3525)(2325 2700);
WIRE 3 2175 (1850 2700)(2325 2700);
WIRE 16 -1 (-2375 3675)(325 3675);
FORCEPROP 2 LAST SIG_NAME VR_PVCCIO_CPU0_PWM1
J 0
(-2300 3674);
DISPLAY 0.617021 (-2300 3674);
PAINT ORANGE (-2300 3674);
WIRE 16 2175 (-1700 4200)(-1025 4200);
WIRE 16 2175 (-1700 4200)(-1700 3800);
WIRE 16 2175 (-1025 4200)(-1025 3800);
WIRE 16 2175 (-1700 3800)(-1025 3800);
WIRE 16 -1 (325 3775)(-575 3775);
FORCEPROP 0 LAST SIG_NAME TP_PVCCIO_CPU0_GL_0
J 0
(-560 3785);
DISPLAY 0.617021 (-560 3785);
PAINT ORANGE (-560 3785);
FORCEPROP 2 LASTPROP $XRERR UNIQUE?
J 0
(-815 3775);
DISPLAY 0.638298 (-815 3775);
PAINT MONO (-815 3775);
DISPLAY INVISIBLE (-815 3775);
WIRE 16 -1 (325 3825)(-575 3825);
FORCEPROP 0 LAST SIG_NAME TP_PVCCIO_CPU0_GL_1
J 0
(-560 3835);
DISPLAY 0.617021 (-560 3835);
PAINT ORANGE (-560 3835);
FORCEPROP 2 LASTPROP $XRERR UNIQUE?
J 0
(-815 3825);
DISPLAY 0.638298 (-815 3825);
PAINT MONO (-815 3825);
DISPLAY INVISIBLE (-815 3825);
WIRE 16 682 (-2550 2975)(-2550 2250);
WIRE 16 682 (-3450 2975)(-2550 2975);
WIRE 16 682 (-2550 2250)(-3450 2250);
WIRE 16 682 (-3450 2250)(-3450 2975);
WIRE 16 -1 (1325 4325)(2625 4325);
FORCEPROP 2 LAST SIG_NAME ISENSE_PVCCIO_CPU0_PH1_IMON
J 2
(2175 4339);
DISPLAY 0.617021 (2175 4339);
PAINT ORANGE (2175 4339);
WIRE 16 -1 (1325 4075)(2025 4075);
FORCEPROP 2 LAST SIG_NAME NC_PVCCIO_CPU0_PH1_P31
J 0
(1417 4085);
DISPLAY 0.617021 (1417 4085);
PAINT ORANGE (1417 4085);
FORCEPROP 2 LASTPROP $XRERR UNIQUE?
J 0
(2055 4075);
DISPLAY 0.638298 (2055 4075);
PAINT MONO (2055 4075);
DISPLAY INVISIBLE (2055 4075);
WIRE 3 2175 (-225 3000)(400 3000);
WIRE 3 2175 (-225 3525)(-225 3000);
WIRE 3 2175 (400 3525)(400 3000);
WIRE 3 2175 (-225 3525)(400 3525);
WIRE 16 -1 (1325 4125)(3100 4125);
FORCEPROP 0 LAST SIG_NAME VR_PVCCIO_CPU0_OCSET
J 0
(1415 4135);
DISPLAY 0.617021 (1415 4135);
PAINT ORANGE (1415 4135);
FORCEPROP 2 LASTPROP $XRERR UNIQUE?
J 0
(1175 4135);
DISPLAY 0.638298 (1175 4135);
PAINT MONO (1175 4135);
DISPLAY INVISIBLE (1175 4135);
WIRE 16 -1 (3100 4125)(3100 4050);
WIRE 16 -1 (325 3575)(25 3575);
WIRE 16 -1 (25 3575)(25 4650);
WIRE 16 -1 (25 3375)(25 3575);
WIRE 16 -1 (25 4650)(2675 4650);
FORCEPROP 2 LAST SIG_NAME VR_PVCCIO_CPU0_AIREF1
J 0
(97 4679);
DISPLAY 0.617021 (97 4679);
PAINT ORANGE (97 4679);
WIRE 16 -1 (1325 3975)(1950 3975);
FORCEPROP 2 LAST SIG_NAME A_TSENSE_PVCCIO_CPU0
J 2
(1800 3989);
DISPLAY 0.617021 (1800 3989);
PAINT ORANGE (1800 3989);
WIRE 16 -1 (1325 3975)(1325 3825);
WIRE 16 -1 (1950 3975)(2400 3975);
WIRE 16 -1 (1950 3900)(1950 3975);
WIRE 16 -1 (1325 3475)(2050 3475);
FORCEPROP 0 LAST VOLTAGE 5
J 0
(1700 3550);
DISPLAY 1.021277 (1700 3550);
PAINT SKYBLUE (1700 3550);
DISPLAY INVISIBLE (1700 3550);
FORCEPROP 2 LAST SIG_NAME VR_PVCCIO_CPU0_PH1_SW
J 0
(1390 3485);
DISPLAY 0.617021 (1390 3485);
PAINT ORANGE (1390 3485);
FORCEPROP 2 LASTPROP $XRERR UNIQUE?
J 0
(1150 3485);
DISPLAY 0.638298 (1150 3485);
PAINT MONO (1150 3485);
DISPLAY INVISIBLE (1150 3485);
WIRE 16 -1 (2050 3475)(2375 3475);
WIRE 16 -1 (2050 3400)(2050 3475);
WIRE 16 -1 (2050 3250)(2050 3125);
DOT 1 (-1975 3775);
DOT 1 (-1975 4325);
DOT 1 (1950 3975);
DOT 1 (1475 3225);
DOT 1 (2050 3475);
DOT 1 (25 3575);
DOT 1 (825 2450);
DOT 1 (1025 2450);
DOT 1 (-3150 3775);
DOT 1 (-2900 3775);
DOT 1 (-2675 3775);
DOT 1 (-2450 3775);
DOT 1 (-2200 3775);
DOT 1 (-1925 1400);
DOT 1 (-1925 1850);
DOT 1 (-950 1400);
DOT 1 (-950 1850);
DOT 1 (-1425 3775);
DOT 1 (-3150 4225);
DOT 1 (-2900 4225);
DOT 1 (-2675 4225);
DOT 1 (-2450 4225);
DOT 1 (-2200 4225);
DOT 1 (-1425 4575);
DOT 1 (-1275 4575);
DOT 1 (-425 4575);
DOT 1 (1475 3275);
DOT 1 (1475 3325);
DOT 1 (2950 2150);
DOT 1 (2950 2575);
DOT 1 (2925 3050);
DOT 1 (2725 3475);
DOT 1 (2925 3475);
DOT 1 (3375 2150);
DOT 1 (3225 3050);
DOT 1 (3375 2575);
DOT 1 (3225 3475);
DOT 1 (3600 3475);
DOT 1 (100 4225);
DOT 1 (175 4125);
FORCENOTE
TP FAB1 CO-LAY WITH TI PARTS 11/16
(2400 3625) 0;
DISPLAY LEFT (2400 3625);
DISPLAY 0.851064 (2400 3625);
PAINT RED (2400 3625);
FORCENOTE
TP FAB1 CO-LAY WITH TI PARTS 11/16
(-1225 3175) 0;
DISPLAY LEFT (-1225 3175);
DISPLAY 0.851064 (-1225 3175);
PAINT RED (-1225 3175);
FORCENOTE
ROOM= PVCCIO_CPU0
(-2073 2881) 0;
DISPLAY LEFT (-2073 2881);
DISPLAY 1.595745 (-2073 2881);
PAINT PURPLE (-2073 2881);
FORCENOTE
SPOF
(-1729 3076) 0;
DISPLAY LEFT (-1729 3076);
DISPLAY 2.340426 (-1729 3076);
PAINT PURPLE (-1729 3076);
FORCENOTE
VR CONTROLLER SIDE
(-875 1611) 0;
DISPLAY LEFT (-875 1611);
DISPLAY 1.021277 (-875 1611);
PAINT PURPLE (-875 1611);
FORCENOTE
TP FAB1 3.01 OHM NEED CHANGE TO 2.2 OHM BUT WAIT FOR SYMBOL
(2325 2775) 0;
DISPLAY LEFT (2325 2775);
DISPLAY 0.851064 (2325 2775);
PAINT RED (2325 2775);
FORCENOTE
TP FAB1 CO-LAY WITH TI PARTS 11/16
(2350 2825) 0;
DISPLAY LEFT (2350 2825);
DISPLAY 0.851064 (2350 2825);
PAINT RED (2350 2825);
FORCENOTE
PLACE ON TOP
(-1705 3725) 0;
DISPLAY LEFT (-1705 3725);
DISPLAY 1.553191 (-1705 3725);
PAINT PURPLE (-1705 3725);
FORCENOTE
BOOM = PROC_VRD_PVCCIO_CPU0
(-3675 375) 0;
DISPLAY LEFT (-3675 375);
DISPLAY 1.276596 (-3675 375);
PAINT PURPLE (-3675 375);
FORCENOTE
ROOM = PVCCIO_CPU0
(-3675 450) 0;
DISPLAY LEFT (-3675 450);
DISPLAY 1.276596 (-3675 450);
PAINT PURPLE (-3675 450);
FORCENOTE
SOCKET SIDE
(-3294 1615) 0;
DISPLAY LEFT (-3294 1615);
DISPLAY 1.021277 (-3294 1615);
PAINT PURPLE (-3294 1615);
FORCENOTE
5MIL WIDTH
(-2704 1201) 0;
DISPLAY LEFT (-2704 1201);
DISPLAY 1.021277 (-2704 1201);
PAINT PURPLE (-2704 1201);
FORCENOTE
SW FREQ=641 KHZ 
(-3425 2325) 0;
DISPLAY LEFT (-3425 2325);
DISPLAY 0.808511 (-3425 2325);
PAINT PURPLE (-3425 2325);
FORCENOTE
IOUT DI/DT =22 A/US
(-3425 2375) 0;
DISPLAY LEFT (-3425 2375);
DISPLAY 0.808511 (-3425 2375);
PAINT PURPLE (-3425 2375);
FORCENOTE
IOUT STEP=14APP
(-3425 2425) 0;
DISPLAY LEFT (-3425 2425);
DISPLAY 0.808511 (-3425 2425);
PAINT PURPLE (-3425 2425);
FORCENOTE
IOUT PK= 19A
(-3425 2475) 0;
DISPLAY LEFT (-3425 2475);
DISPLAY 0.808511 (-3425 2475);
PAINT PURPLE (-3425 2475);
FORCENOTE
IOUT TDC=11A
(-3425 2525) 0;
DISPLAY LEFT (-3425 2525);
DISPLAY 0.808511 (-3425 2525);
PAINT PURPLE (-3425 2525);
FORCENOTE
TOTAL TOL = 1.057VMAX/0.937VMIN
(-3425 2575) 0;
DISPLAY LEFT (-3425 2575);
DISPLAY 0.808511 (-3425 2575);
PAINT PURPLE (-3425 2575);
FORCENOTE
DC TOL = +/-5MV
(-3425 2625) 0;
DISPLAY LEFT (-3425 2625);
DISPLAY 0.808511 (-3425 2625);
PAINT PURPLE (-3425 2625);
FORCENOTE
VBOOT=1.0V 
(-3425 2275) 0;
DISPLAY LEFT (-3425 2275);
DISPLAY 0.808511 (-3425 2275);
PAINT PURPLE (-3425 2275);
FORCENOTE
VOUT=1.0V (TYP) SVID
(-3425 2725) 0;
DISPLAY LEFT (-3425 2725);
DISPLAY 0.808511 (-3425 2725);
PAINT PURPLE (-3425 2725);
FORCENOTE
RIPPLE = +/- 10MV
(-3425 2675) 0;
DISPLAY LEFT (-3425 2675);
DISPLAY 0.808511 (-3425 2675);
PAINT PURPLE (-3425 2675);
FORCENOTE
SPOF
(-1325 2017) 0;
DISPLAY LEFT (-1325 2017);
DISPLAY 1.340426 (-1325 2017);
PAINT PURPLE (-1325 2017);
FORCENOTE
5MIL SPACING
(-2704 1126) 0;
DISPLAY LEFT (-2704 1126);
DISPLAY 1.021277 (-2704 1126);
PAINT PURPLE (-2704 1126);
FORCENOTE
ROUTE AS DIFF PAIR
(-2694 1266) 0;
DISPLAY LEFT (-2694 1266);
DISPLAY 1.021277 (-2694 1266);
PAINT PURPLE (-2694 1266);
QUIT
